G04 ================== begin FILE IDENTIFICATION RECORD ==================*
G04 Layout Name:  D:/<user>/Wistron_project/16316-1/gbr-0621/16316-1.brd*
G04 Film Name:    SE_REF_L6*
G04 File Format:  Gerber RS274X*
G04 File Origin:  Cadence Allegro 16.5-S056*
G04 Origin Date:  Wed Jun 21 09:32:35 2017*
G04 *
G04 Layer:  BOARD GEOMETRY/SE_REF_L6_TBL*
G04 Layer:  BOARD GEOMETRY/SE_REF_L6_L6*
G04 Layer:  BOARD GEOMETRY/PANEL_OUTLINE*
G04 *
G04 Offset:    (0.00 0.00)*
G04 Mirror:    No*
G04 Mode:      Positive*
G04 Rotation:  0*
G04 FullContactRelief:  No*
G04 UndefLineWidth:     6.00*
G04 ================== end FILE IDENTIFICATION RECORD ====================*
%FSLAX35Y35*MOIN*%
%IR0*IPPOS*OFA0.00000B0.00000*MIA0B0*SFA1.00000B1.00000*%
%ADD10C,.02*%
%ADD11C,.005*%
%ADD12C,.006*%
G75*
%LPD*%
G75*
G54D10*
G01X877071Y467216D02*
X1594571D01*
G01X877071Y536516D02*
Y467216D01*
G01Y536516D02*
X1594571D01*
G01X877071Y501866D02*
X1594571D01*
G01X1052071Y536516D02*
Y467216D01*
G01X1279571Y536516D02*
Y467216D01*
G01X1384571Y536516D02*
Y467216D01*
G01X1594571Y536516D02*
Y467216D01*
G54D11*
G01X82776Y250280D02*
X49320D01*
G01X67893Y263900D02*
X80688Y276695D01*
G01X57303Y263900D02*
X67893D01*
G01X49320Y255917D02*
X57303Y263900D01*
G01X49320Y250280D02*
Y255917D01*
G01X47750Y248180D02*
X80366D01*
G01X45650Y250280D02*
X47750Y248180D01*
G01X45650Y256247D02*
Y250280D01*
G01X58003Y268600D02*
X45650Y256247D01*
G01X69473Y268600D02*
X58003D01*
G01X80688Y279815D02*
X69473Y268600D01*
G01X39218Y243531D02*
X32469Y250280D01*
G01X77036Y243531D02*
X39218D01*
G01X59600Y334880D02*
X58900Y334180D01*
G01X59600Y362301D02*
Y334880D01*
G01X49635Y356235D02*
Y371606D01*
G01X41325Y347925D02*
X49635Y356235D01*
G01X41325Y334268D02*
Y347925D01*
G01X39000Y359700D02*
Y362300D01*
G01X35453Y356153D02*
X39000Y359700D01*
G01X35453Y333998D02*
Y356153D01*
G01X54851Y314600D02*
X35453Y333998D01*
G01X80900Y314600D02*
X54851D01*
G01X37000Y360529D02*
Y362200D01*
G01X33453Y356982D02*
X37000Y360529D01*
G01X33453Y333047D02*
Y356982D01*
G01X53900Y312600D02*
X33453Y333047D01*
G01X80071Y312600D02*
X53900D01*
G01X62325Y362127D02*
Y334068D01*
G01X47635Y357064D02*
Y372435D01*
G01X39000Y348429D02*
X47635Y357064D01*
G01X39000Y335480D02*
Y348429D01*
G01X37900Y334380D02*
X39000Y335480D01*
G01X76300Y379001D02*
X59600Y362301D01*
G01X76300Y401693D02*
Y379001D01*
G01X157774Y483167D02*
X76300Y401693D01*
G01X61600Y402203D02*
X144564Y485167D01*
G01X61600Y383571D02*
Y402203D01*
G01X49635Y371606D02*
X61600Y383571D01*
G01X39000Y362300D02*
X40100Y363400D01*
G01X37000Y362200D02*
X35800Y363400D01*
G01X78515Y378317D02*
X62325Y362127D01*
G01X59600Y403592D02*
X143175Y487167D01*
G01X59600Y384400D02*
Y403592D01*
G01X47635Y372435D02*
X59600Y384400D01*
G01X127500Y105600D02*
Y137000D01*
G01X135373Y97727D02*
X127500Y105600D01*
G01X204773Y97727D02*
X135373D01*
G01X130850Y105950D02*
Y137350D01*
G01X135673Y101127D02*
X130850Y105950D01*
G01X164020Y101127D02*
X135673D01*
G01X125500Y104400D02*
Y136171D01*
G01X134173Y95727D02*
X125500Y104400D01*
G01X180087Y95727D02*
X134173D01*
G01X133919Y93152D02*
X179833D01*
G01X123500Y103571D02*
X133919Y93152D01*
G01X123500Y135342D02*
Y103571D01*
G01X118650Y102057D02*
Y133828D01*
G01X132055Y88652D02*
X118650Y102057D01*
G01X176897Y88652D02*
X132055D01*
G01X105742Y158758D02*
Y230475D01*
G01X127500Y137000D02*
X105742Y158758D01*
G01X107742Y160458D02*
Y326275D01*
G01X130850Y137350D02*
X107742Y160458D01*
G01X103034Y158637D02*
Y230022D01*
G01X125500Y136171D02*
X103034Y158637D01*
G01X101034Y157808D02*
X123500Y135342D01*
G01X101034Y227512D02*
Y157808D01*
G01X96448Y156030D02*
Y224119D01*
G01X118650Y133828D02*
X96448Y156030D01*
G01X105742Y230475D02*
X93884Y242333D01*
G01X103034Y230022D02*
X82776Y250280D01*
G01X80366Y248180D02*
X101034Y227512D01*
G01X96448Y224119D02*
X77036Y243531D01*
G01X83000Y298600D02*
X80600Y301000D01*
G01X83000Y279007D02*
Y298600D01*
G01X80688Y276695D02*
X83000Y279007D01*
G01X78400Y283983D02*
Y307100D01*
G01X80688Y281695D02*
X78400Y283983D01*
G01X80688Y281695D02*
Y279815D01*
G01X84021Y343528D02*
Y373896D01*
G01X81050Y340557D02*
X84021Y343528D01*
G01X81050Y335030D02*
Y340557D01*
G01X80600Y334580D02*
X81050Y335030D01*
G01X106500Y355899D02*
X139447Y388846D01*
G01X106500Y333900D02*
Y355899D01*
G01X84025Y340703D02*
Y334468D01*
G01X86021Y342699D02*
X84025Y340703D01*
G01X86021Y374725D02*
Y342699D01*
G01X99950Y358650D02*
X96445Y362155D01*
G01X99950Y333733D02*
Y358650D01*
G01X102333Y331350D02*
X99950Y333733D01*
G01X102667Y331350D02*
X102333D01*
G01X107742Y326275D02*
X102667Y331350D01*
G01X83144Y312356D02*
X80900Y314600D01*
G01X83144Y307144D02*
Y312356D01*
G01X80600Y304600D02*
X83144Y307144D01*
G01X80600Y301000D02*
Y304600D01*
G01X81144Y311527D02*
X80071Y312600D01*
G01X81144Y309844D02*
Y311527D01*
G01X80700Y309400D02*
X81144Y309844D01*
G01X78400Y307100D02*
X80700Y309400D01*
G01X102400Y357069D02*
Y333900D01*
G01X138588Y393257D02*
X102400Y357069D01*
G01X81795Y395034D02*
X147661Y460900D01*
G01X81795Y376122D02*
Y395034D01*
G01X84021Y373896D02*
X81795Y376122D01*
G01X107582Y412124D02*
X150358Y454900D01*
G01X107582Y391266D02*
Y412124D01*
G01X83795Y376951D02*
X86021Y374725D01*
G01X83795Y394205D02*
Y376951D01*
G01X148490Y458900D02*
X83795Y394205D01*
G01X104900Y412271D02*
Y412200D01*
G01X149529Y456900D02*
X104900Y412271D01*
G01X96445Y403745D02*
X104900Y412200D01*
G01X96445Y362155D02*
Y403745D01*
G01X126869Y397859D02*
X112023Y383013D01*
G01X184486Y397859D02*
X126869D01*
G01X78515Y400486D02*
Y378317D01*
G01X159196Y481167D02*
X78515Y400486D01*
G01X108624Y383400D02*
X106709D01*
G01X127333Y402109D02*
X108624Y383400D01*
G01X185164Y402109D02*
X127333D01*
G01X226896Y48918D02*
X180087Y95727D01*
G01X179833Y93152D02*
X226067Y46918D01*
G01X229496Y36053D02*
X176897Y88652D01*
G01X181559Y388846D02*
X201454Y368951D01*
G01X139447Y388846D02*
X181559D01*
G01X208648Y373697D02*
X184486Y397859D01*
G01X183023Y393257D02*
X138588D01*
G01X204749Y371531D02*
X183023Y393257D01*
G01X212198Y375075D02*
X185164Y402109D01*
G01X147661Y460900D02*
X262587D01*
G01X150358Y454900D02*
X254300D01*
G01X259936Y458900D02*
X148490D01*
G01X257334Y456900D02*
X149529D01*
G01X250079Y483167D02*
X157774D01*
G01X144564Y485167D02*
X253149D01*
G01X247769Y481167D02*
X159196D01*
G01X143175Y487167D02*
X256158D01*
G01X307337Y48918D02*
X226896D01*
G01X226067Y46918D02*
X306508D01*
G01X250137Y36053D02*
X229496D01*
G01X250137D02*
X320239D01*
G01X233759Y68741D02*
X204773Y97727D01*
G01X233759Y64752D02*
Y68741D01*
G01X255154Y69177D02*
X279377D01*
G01X271283Y72600D02*
X255300D01*
G01X253156Y333513D02*
X245943Y326300D01*
G01X259027Y333513D02*
X253156D01*
G01X292850Y367336D02*
X259027Y333513D01*
G01X260305Y349230D02*
X304473Y393398D01*
G01X254029Y349230D02*
X260305D01*
G01X234399Y329600D02*
X254029Y349230D01*
G01X230400Y329600D02*
X234399D01*
G01X260514Y340658D02*
X292018Y372162D01*
G01X253944Y340658D02*
X260514D01*
G01X235486Y322200D02*
X253944Y340658D01*
G01X205590Y322200D02*
X235486D01*
G01X201454Y326336D02*
X205590Y322200D01*
G01X201454Y368951D02*
Y326336D01*
G01X260801Y355384D02*
X302902Y397485D01*
G01X230873Y355384D02*
X260801D01*
G01X218300Y342811D02*
X230873Y355384D01*
G01X218300Y330000D02*
Y342811D01*
G01X220400Y328600D02*
X218400Y326600D01*
G01X220400Y342082D02*
Y328600D01*
G01X231702Y353384D02*
X220400Y342082D01*
G01X261630Y353384D02*
X231702D01*
G01X303731Y395485D02*
X261630Y353384D01*
G01X208648Y328452D02*
Y373697D01*
G01X262097Y323619D02*
X261365Y324351D01*
G01X262097Y313898D02*
Y323619D01*
G01X266631Y309364D02*
X262097Y313898D01*
G01X204749Y327223D02*
Y371531D01*
G01X207772Y324200D02*
X204749Y327223D01*
G01X234657Y324200D02*
X207772D01*
G01X253621Y343164D02*
X234657Y324200D01*
G01X259897Y343164D02*
X253621D01*
G01X291419Y374686D02*
X259897Y343164D01*
G01X260048Y337363D02*
X292847Y370162D01*
G01X253763Y337363D02*
X260048D01*
G01X246100Y329700D02*
X253763Y337363D01*
G01X212198Y328316D02*
Y375075D01*
G01X260619Y346715D02*
X305302Y391398D01*
G01X254343Y346715D02*
X260619D01*
G01X233828Y326200D02*
X254343Y346715D01*
G01X230400Y326200D02*
X233828D01*
G01X259800Y449400D02*
Y423400D01*
G01Y412659D02*
X266500Y405959D01*
G01X259800Y423400D02*
Y412659D01*
G01X262587Y460900D02*
X307811Y415676D01*
G01X254300Y454900D02*
X259800Y449400D01*
G01X305825Y413011D02*
X259936Y458900D01*
G01X304234Y410000D02*
X257334Y456900D01*
G01X310396Y422850D02*
X250079Y483167D01*
G01X253149Y485167D02*
X313466Y424850D01*
G01X310936Y418000D02*
X247769Y481167D01*
G01X256158Y487167D02*
X316475Y426850D01*
G01X355911Y97492D02*
X307337Y48918D01*
G01X308165Y46917D02*
X357911Y96663D01*
G01X306509Y46917D02*
X308165D01*
G01X306508Y46918D02*
X306509Y46917D01*
G01X320239Y36053D02*
X327158Y29134D01*
G01X283385Y108983D02*
X302555Y128153D01*
G01X283385Y100227D02*
Y108983D01*
G01X311867Y85551D02*
X343911Y117595D01*
G01X295751Y85551D02*
X311867D01*
G01X279377Y69177D02*
X295751Y85551D01*
G01X311182Y82037D02*
X345911Y116766D01*
G01X311182Y62800D02*
Y82037D01*
G01X270937Y87862D02*
X272937Y85862D01*
G01X270937Y114890D02*
Y87862D01*
G01X272937Y114061D02*
Y90362D01*
G01X268937Y86454D02*
Y115719D01*
G01X273206Y82185D02*
X268937Y86454D01*
G01X278039Y82185D02*
X273206D01*
G01X287385Y110154D02*
X304555Y127324D01*
G01X287385Y100227D02*
Y110154D01*
G01X266895Y116506D02*
Y100227D01*
G01X314772Y108292D02*
Y119714D01*
G01X286283Y87600D02*
X271283Y72600D01*
G01X311087Y87600D02*
X286283D01*
G01X341600Y118113D02*
X311087Y87600D01*
G01X312772Y113052D02*
Y120543D01*
G01X309929Y110209D02*
X312772Y113052D01*
G01X306196Y110209D02*
X309929D01*
G01X276961Y111946D02*
X285893Y120878D01*
G01X276961Y98893D02*
Y111946D01*
G01X280298Y95556D02*
X276961Y98893D01*
G01X278418Y92325D02*
X283393D01*
G01X274937Y95806D02*
X278418Y92325D01*
G01X274937Y113232D02*
Y95806D01*
G01X281950Y120245D02*
X274937Y113232D01*
G01X303334Y111939D02*
X308579Y117184D01*
G01X303334Y108559D02*
Y111939D01*
G01X297632Y102857D02*
X303334Y108559D01*
G01X294015Y102857D02*
X297632D01*
G01X291385Y100227D02*
X294015Y102857D01*
G01X316772Y107675D02*
Y118885D01*
G01X309324Y100227D02*
X316772Y107675D01*
G01X295385Y100227D02*
X309324D01*
G01X313766Y61276D02*
X311182Y58692D01*
G01X313766Y81792D02*
Y61276D01*
G01X347911Y115937D02*
X313766Y81792D01*
G01X292385Y108227D02*
X300949Y116791D01*
G01X318773Y109636D02*
Y108083D01*
G01X321582Y112445D02*
X318773Y109636D01*
G01X321582Y116924D02*
Y112445D01*
G01X315900Y77800D02*
X351911Y113811D01*
G01X315900Y60500D02*
Y77800D01*
G01X312091Y56691D02*
X315900Y60500D01*
G01X298009Y56691D02*
X312091D01*
G01X288000Y66700D02*
X298009Y56691D01*
G01X276700Y66700D02*
X288000D01*
G01X302555Y128153D02*
Y245463D01*
G01X310711Y121311D02*
Y113820D01*
G01X312780Y123380D02*
X310711Y121311D01*
G01X312780Y155522D02*
Y123380D01*
G01X316301Y159043D02*
X312780Y155522D01*
G01X316301Y235939D02*
Y159043D01*
G01X277950Y121903D02*
X270937Y114890D01*
G01X277950Y259104D02*
Y121903D01*
G01X279950Y121074D02*
X272937Y114061D01*
G01X279950Y258275D02*
Y121074D01*
G01X275950Y122732D02*
Y261326D01*
G01X268937Y115719D02*
X275950Y122732D01*
G01X304555Y127324D02*
Y244634D01*
G01X324026Y116539D02*
X327343Y119856D01*
G01X324026Y115936D02*
Y116539D01*
G01X304579Y118842D02*
X304529Y118792D01*
G01X304579Y124519D02*
Y118842D01*
G01X306555Y126495D02*
X304579Y124519D01*
G01X306555Y243805D02*
Y126495D01*
G01X270409Y120020D02*
X266895Y116506D01*
G01X270409Y260668D02*
Y120020D01*
G01X321343Y131271D02*
Y122343D01*
G01X323250Y133178D02*
X321343Y131271D01*
G01X323250Y151847D02*
Y133178D01*
G01X326342Y154939D02*
X323250Y151847D01*
G01X320301Y157385D02*
Y234281D01*
G01X316780Y153864D02*
X320301Y157385D01*
G01X316780Y121722D02*
Y153864D01*
G01X314772Y119714D02*
X316780Y121722D01*
G01X318301Y158214D02*
Y235110D01*
G01X314780Y154693D02*
X318301Y158214D01*
G01X314780Y122551D02*
Y154693D01*
G01X312772Y120543D02*
X314780Y122551D01*
G01X324301Y155727D02*
Y231090D01*
G01X321051Y152477D02*
X324301Y155727D01*
G01X321051Y134028D02*
Y152477D01*
G01X299623Y128050D02*
Y272290D01*
G01X292451Y120878D02*
X299623Y128050D01*
G01X285893Y120878D02*
X292451D01*
G01X281950Y257446D02*
Y120245D01*
G01X319533Y117704D02*
Y114283D01*
G01X323343Y121514D02*
X319533Y117704D01*
G01X323343Y130442D02*
Y121514D01*
G01X325250Y132349D02*
X323343Y130442D01*
G01X314301Y159872D02*
Y237430D01*
G01X310780Y156351D02*
X314301Y159872D01*
G01X310780Y124209D02*
Y156351D01*
G01X308579Y122008D02*
X310780Y124209D01*
G01X308579Y117184D02*
Y122008D01*
G01X322301Y156556D02*
Y233452D01*
G01X318780Y153035D02*
X322301Y156556D01*
G01X318780Y120893D02*
Y153035D01*
G01X316772Y118885D02*
X318780Y120893D01*
G01X312300Y160700D02*
Y240081D01*
G01X308555Y156955D02*
X312300Y160700D01*
G01X308555Y124813D02*
Y156955D01*
G01X306579Y122837D02*
X308555Y124813D01*
G01X306579Y118013D02*
Y122837D01*
G01X305357Y116791D02*
X306579Y118013D01*
G01X300949Y116791D02*
X305357D01*
G01X325343Y120685D02*
X321582Y116924D01*
G01X325650Y245288D02*
X316301Y235939D01*
G01X320301Y234281D02*
X335800Y249780D01*
G01X318301Y235110D02*
X331300Y248109D01*
G01X324301Y231090D02*
X362478Y269267D01*
G01X314301Y237430D02*
X321731Y244860D01*
G01X322301Y233452D02*
X338100Y249251D01*
G01X322370Y276707D02*
Y303116D01*
G01X308250Y262587D02*
X322370Y276707D01*
G01X308250Y255515D02*
Y262587D01*
G01X308292Y255473D02*
X308250Y255515D01*
G01X308292Y253654D02*
Y255473D01*
G01X308293Y253653D02*
X308292Y253654D01*
G01X308293Y251201D02*
Y253653D01*
G01X302555Y245463D02*
X308293Y251201D01*
G01X316150Y299559D02*
Y314268D01*
G01X315455Y298864D02*
X316150Y299559D01*
G01X315455Y282793D02*
Y298864D01*
G01X302184Y269522D02*
X315455Y282793D01*
G01X302184Y262720D02*
Y269522D01*
G01X302262Y262642D02*
X302184Y262720D01*
G01X305730Y286884D02*
X277950Y259104D01*
G01X305730Y297700D02*
Y286884D01*
G01X303709Y299721D02*
X305730Y297700D01*
G01X307730Y286055D02*
X279950Y258275D01*
G01X307730Y298529D02*
Y286055D01*
G01X305709Y300550D02*
X307730Y298529D01*
G01X297151Y282527D02*
Y304664D01*
G01X275950Y261326D02*
X297151Y282527D01*
G01X310250Y261758D02*
X325729Y277237D01*
G01X310250Y256344D02*
Y261758D01*
G01X310292Y256302D02*
X310250Y256344D01*
G01X310292Y254483D02*
Y256302D01*
G01X310294Y254481D02*
X310292Y254483D01*
G01X310294Y252825D02*
Y254481D01*
G01X310293Y252824D02*
X310294Y252825D01*
G01X310293Y250372D02*
Y252824D01*
G01X304555Y244634D02*
X310293Y250372D01*
G01X312293Y249543D02*
X306555Y243805D01*
G01X312293Y251995D02*
Y249543D01*
G01X312294Y251996D02*
X312293Y251995D01*
G01X312294Y255310D02*
Y251996D01*
G01X312292Y255312D02*
X312294Y255310D01*
G01X312292Y257131D02*
Y255312D01*
G01X312250Y257173D02*
X312292Y257131D01*
G01X312250Y260929D02*
Y257173D01*
G01X334032Y282711D02*
X312250Y260929D01*
G01X294817Y285076D02*
X270409Y260668D01*
G01X294817Y305159D02*
Y285076D01*
G01X317455Y298035D02*
X320149Y300729D01*
G01X317455Y281964D02*
Y298035D01*
G01X304262Y268771D02*
X317455Y281964D01*
G01X304262Y254855D02*
Y268771D01*
G01X306292Y252825D02*
X304262Y254855D01*
G01X312030Y284697D02*
Y312977D01*
G01X299623Y272290D02*
X312030Y284697D01*
G01X310030Y285526D02*
X281950Y257446D01*
G01X310030Y313806D02*
Y285526D01*
G01X321731Y263981D02*
X331236Y273486D01*
G01X321731Y244860D02*
Y263981D01*
G01X317707Y263557D02*
X337732Y283582D01*
G01X317707Y245488D02*
Y263557D01*
G01X312300Y240081D02*
X317707Y245488D01*
G01X322370Y303116D02*
X330032Y310778D01*
G01X324733Y327250D02*
X327867D01*
G01X323650Y326167D02*
X324733Y327250D01*
G01X323650Y321768D02*
Y326167D01*
G01X316150Y314268D02*
X323650Y321768D01*
G01X303709Y308393D02*
Y299721D01*
G01X305348Y310032D02*
X303709Y308393D01*
G01X305348Y314782D02*
Y310032D01*
G01X310500Y319934D02*
X305348Y314782D01*
G01X310500Y331752D02*
Y319934D01*
G01X336771Y358023D02*
X310500Y331752D01*
G01X305709Y307564D02*
Y300550D01*
G01X307348Y309203D02*
X305709Y307564D01*
G01X307348Y313953D02*
Y309203D01*
G01X312500Y319105D02*
X307348Y313953D01*
G01X312500Y330923D02*
Y319105D01*
G01X336812Y355235D02*
X312500Y330923D01*
G01X323850Y351850D02*
X332051Y360051D01*
G01X321614Y351850D02*
X323850D01*
G01X314200Y344436D02*
X321614Y351850D01*
G01X314200Y338281D02*
Y344436D01*
G01X308200Y332281D02*
X314200Y338281D01*
G01X308200Y320463D02*
Y332281D01*
G01X303348Y315611D02*
X308200Y320463D01*
G01X303348Y310861D02*
Y315611D01*
G01X297151Y304664D02*
X303348Y310861D01*
G01X286892Y341898D02*
X319054Y374060D01*
G01X286892Y316408D02*
Y341898D01*
G01X288536Y314764D02*
X286892Y316408D01*
G01X299348Y309690D02*
X294817Y305159D01*
G01X299348Y321348D02*
Y309690D01*
G01X303865Y325865D02*
X299348Y321348D01*
G01X303865Y341038D02*
Y325865D01*
G01X325666Y362839D02*
X303865Y341038D01*
G01X320149Y309474D02*
X325514Y314839D01*
G01X320149Y300729D02*
Y309474D01*
G01X293019Y309364D02*
X266631D01*
G01X297348Y313693D02*
X293019Y309364D01*
G01X297348Y322177D02*
Y313693D01*
G01X298100Y322929D02*
X297348Y322177D01*
G01X298100Y340617D02*
Y322929D01*
G01X325277Y367794D02*
X298100Y340617D01*
G01X284892Y323536D02*
X275696Y314340D01*
G01X284892Y342727D02*
Y323536D01*
G01X318225Y376060D02*
X284892Y342727D01*
G01X324023Y332340D02*
X339606Y347923D01*
G01X324023Y329369D02*
Y332340D01*
G01X318567Y323913D02*
X324023Y329369D01*
G01X318567Y319514D02*
Y323913D01*
G01X312030Y312977D02*
X318567Y319514D01*
G01X316500Y320276D02*
X310030Y313806D01*
G01X316500Y324675D02*
Y320276D01*
G01X322023Y330198D02*
X316500Y324675D01*
G01X322023Y334606D02*
Y330198D01*
G01X331850Y344433D02*
X322023Y334606D01*
G01X296100Y342083D02*
X323811Y369794D01*
G01X296100Y324233D02*
Y342083D01*
G01X295348Y323481D02*
X296100Y324233D01*
G01X295348Y314903D02*
Y323481D01*
G01X292112Y311667D02*
X295348Y314903D01*
G01X267157Y311667D02*
X292112D01*
G01X264097Y314727D02*
X267157Y311667D01*
G01X264097Y323083D02*
Y314727D01*
G01X265365Y324351D02*
X264097Y323083D01*
G01X306448Y367336D02*
X292850D01*
G01X317172Y378060D02*
X306448Y367336D01*
G01X387330Y378060D02*
X317172D01*
G01X307811Y415676D02*
X375175D01*
G01X304473Y393398D02*
X386137D01*
G01X266500Y405959D02*
Y364000D01*
G01X312298Y382060D02*
X388988D01*
G01X302400Y372162D02*
X312298Y382060D01*
G01X292018Y372162D02*
X302400D01*
G01X375011Y413011D02*
X305825D01*
G01X360000Y410000D02*
X304234D01*
G01X302902Y397485D02*
X387708D01*
G01X373893Y422850D02*
X310396D01*
G01X386879Y395485D02*
X303731D01*
G01X319054Y374060D02*
X385672D01*
G01X375914Y418000D02*
X310936D01*
G01X386501Y376060D02*
X318225D01*
G01X302095Y374686D02*
X291419D01*
G01X311709Y384300D02*
X302095Y374686D01*
G01X389577Y384300D02*
X311709D01*
G01X313127Y380060D02*
X388159D01*
G01X303229Y370162D02*
X313127Y380060D01*
G01X292847Y370162D02*
X303229D01*
G01X305302Y391398D02*
X385308D01*
G01X323811Y369794D02*
X387109D01*
G01X313466Y424850D02*
X374722D01*
G01X316475Y426850D02*
X375551D01*
G01X327158Y29134D02*
X338583D01*
G01X349911Y114763D02*
X329722Y94574D01*
G01X355911Y134858D02*
Y97492D01*
G01X357911Y96663D02*
Y131022D01*
G01X333649Y112991D02*
X328711Y108053D01*
G01X333649Y126603D02*
Y112991D01*
G01X353911Y112763D02*
Y135934D01*
G01X335722Y94574D02*
X353911Y112763D01*
G01X349911Y136954D02*
Y114763D01*
G01X347879Y162970D02*
X365773Y180864D01*
G01X347879Y148186D02*
Y162970D01*
G01X343911Y144218D02*
X347879Y148186D01*
G01X343911Y117595D02*
Y144218D01*
G01X351880Y164142D02*
X366344Y178606D01*
G01X351880Y148380D02*
Y164142D01*
G01X345911Y142411D02*
X351880Y148380D01*
G01X345911Y116766D02*
Y142411D01*
G01X336946Y151398D02*
Y191749D01*
G01X333250Y147702D02*
X336946Y151398D01*
G01X333250Y129033D02*
Y147702D01*
G01X331649Y127432D02*
X333250Y129033D01*
G01X331649Y126111D02*
Y127432D01*
G01X359723Y138670D02*
X355911Y134858D01*
G01X359723Y162328D02*
Y138670D01*
G01X369828Y172433D02*
X359723Y162328D01*
G01X370061Y172433D02*
X369828D01*
G01X371316Y169078D02*
X374616Y172378D01*
G01X369815Y169078D02*
X371316D01*
G01X361758Y161021D02*
X369815Y169078D01*
G01X361758Y134869D02*
Y161021D01*
G01X357911Y131022D02*
X361758Y134869D01*
G01X332763Y152873D02*
Y196120D01*
G01X329250Y149360D02*
X332763Y152873D01*
G01X329250Y130691D02*
Y149360D01*
G01X327343Y128784D02*
X329250Y130691D01*
G01X327343Y119856D02*
Y128784D01*
G01X335535Y128489D02*
X333649Y126603D01*
G01X335535Y147158D02*
Y128489D01*
G01X339879Y151502D02*
X335535Y147158D01*
G01X339879Y191853D02*
Y151502D01*
G01X326342Y226921D02*
Y154939D01*
G01X341600Y141200D02*
Y118113D01*
G01X342000Y141600D02*
X341600Y141200D01*
G01X334791Y152072D02*
Y193126D01*
G01X331250Y148531D02*
X334791Y152072D01*
G01X331250Y129862D02*
Y148531D01*
G01X329343Y127955D02*
X331250Y129862D01*
G01X329343Y115143D02*
Y127955D01*
G01X328600Y114400D02*
X329343Y115143D01*
G01X345879Y149015D02*
X341913Y145049D01*
G01X345879Y189366D02*
Y149015D01*
G01X339535Y124724D02*
X339049Y124238D01*
G01X339535Y145500D02*
Y124724D01*
G01X343879Y149844D02*
X339535Y145500D01*
G01X343879Y190195D02*
Y149844D01*
G01X337535Y127660D02*
X335994Y126119D01*
G01X337535Y146329D02*
Y127660D01*
G01X341879Y150673D02*
X337535Y146329D01*
G01X341879Y191024D02*
Y150673D01*
G01X373050Y174577D02*
X374915Y176442D01*
G01X367973Y174577D02*
X373050D01*
G01X357723Y164327D02*
X367973Y174577D01*
G01X357723Y139746D02*
Y164327D01*
G01X353911Y135934D02*
X357723Y139746D01*
G01X325250Y151018D02*
Y132349D01*
G01X328342Y154110D02*
X325250Y151018D01*
G01X328342Y226092D02*
Y154110D01*
G01X347911Y140911D02*
Y115937D01*
G01X353880Y146880D02*
X347911Y140911D01*
G01X353880Y163313D02*
Y146880D01*
G01X367144Y176577D02*
X353880Y163313D01*
G01X325343Y129613D02*
Y120685D01*
G01X327250Y131520D02*
X325343Y129613D01*
G01X327250Y150189D02*
Y131520D01*
G01X330342Y153281D02*
X327250Y150189D01*
G01X330342Y224112D02*
Y153281D01*
G01X355500Y140352D02*
Y144500D01*
G01X351911Y136763D02*
X355500Y140352D01*
G01X351911Y113811D02*
Y136763D01*
G01X385300Y218800D02*
X389304Y222804D01*
G01X385300Y210409D02*
Y218800D01*
G01X382391Y207500D02*
X385300Y210409D01*
G01X373036Y207500D02*
X382391D01*
G01X370570Y205034D02*
X373036Y207500D01*
G01X370570Y198219D02*
Y205034D01*
G01X371019Y180864D02*
X372517Y182362D01*
G01X365773Y180864D02*
X371019D01*
G01X370970Y178606D02*
X371124Y178760D01*
G01X366344Y178606D02*
X370970D01*
G01X364570Y208299D02*
X390942Y234671D01*
G01X364570Y193684D02*
Y208299D01*
G01X366460Y191794D02*
X364570Y193684D01*
G01X350570Y215035D02*
X380751Y245216D01*
G01X350570Y205373D02*
Y215035D01*
G01X336946Y191749D02*
X350570Y205373D01*
G01X366570Y207470D02*
X389681Y230581D01*
G01X366570Y196561D02*
Y207470D01*
G01X367049Y196082D02*
X366570Y196561D01*
G01X367049Y196049D02*
Y196082D01*
G01X368558Y194540D02*
X367049Y196049D01*
G01X382156Y203247D02*
X389784Y210875D01*
G01X382156Y196775D02*
Y203247D01*
G01X379989Y194608D02*
X382156Y196775D01*
G01X379415Y194608D02*
X379989D01*
G01X362570Y209670D02*
X389000Y236100D01*
G01X362570Y189965D02*
Y209670D01*
G01X364169Y188366D02*
X362570Y189965D01*
G01X346568Y233791D02*
X365477Y252700D01*
G01X346568Y209925D02*
Y233791D01*
G01X332763Y196120D02*
X346568Y209925D01*
G01X352570Y204544D02*
X339879Y191853D01*
G01X352570Y213970D02*
Y204544D01*
G01X388055Y249455D02*
X352570Y213970D01*
G01X364815Y265394D02*
X326342Y226921D01*
G01X348568Y232962D02*
X365506Y249900D01*
G01X348568Y206903D02*
Y232962D01*
G01X334791Y193126D02*
X348568Y206903D01*
G01X377182Y187487D02*
X391938Y202243D01*
G01X371390Y187487D02*
X377182D01*
G01X368263Y184360D02*
X371390Y187487D01*
G01X362260Y184360D02*
X368263D01*
G01X358570Y202057D02*
X345879Y189366D01*
G01X358570Y211483D02*
Y202057D01*
G01X388795Y241708D02*
X358570Y211483D01*
G01X356570Y202886D02*
X343879Y190195D01*
G01X356570Y212312D02*
Y202886D01*
G01X389903Y245645D02*
X356570Y212312D01*
G01X354570Y203715D02*
X341879Y191024D01*
G01X354570Y213141D02*
Y203715D01*
G01X388629Y247200D02*
X354570Y213141D01*
G01X360570Y210654D02*
X388516Y238600D01*
G01X360570Y200274D02*
Y210654D01*
G01X351723Y191427D02*
X360570Y200274D01*
G01X351723Y178499D02*
Y191427D01*
G01X365643Y263393D02*
X328342Y226092D01*
G01X371770Y176577D02*
X367144D01*
G01X376306Y181113D02*
X371770Y176577D01*
G01X376306Y182715D02*
Y181113D01*
G01X361231Y255001D02*
X330342Y224112D01*
G01X382994Y219994D02*
X389797Y226797D01*
G01X382994Y213900D02*
Y219994D01*
G01X382294Y213200D02*
X382994Y213900D01*
G01X375400Y213200D02*
X382294D01*
G01X368570Y206370D02*
X375400Y213200D01*
G01X368570Y197390D02*
Y206370D01*
G01X370559Y195401D02*
X368570Y197390D01*
G01X370559Y190904D02*
Y195401D01*
G01X366015Y186360D02*
X370559Y190904D01*
G01X357064Y186360D02*
X366015D01*
G01X354143Y183439D02*
X357064Y186360D01*
G01X325650Y265071D02*
Y245288D01*
G01X331079Y270500D02*
X325650Y265071D01*
G01X341546Y270500D02*
X331079D01*
G01X357500Y286454D02*
X341546Y270500D01*
G01X357500Y291295D02*
Y286454D01*
G01X378155Y311950D02*
X357500Y291295D01*
G01X386150Y254150D02*
X401138D01*
G01X380751Y248751D02*
X386150Y254150D01*
G01X380751Y245216D02*
Y248751D01*
G01X325729Y277237D02*
Y303646D01*
G01X378571Y252700D02*
X388264Y262393D01*
G01X365477Y252700D02*
X378571D01*
G01X334032Y313342D02*
Y282711D01*
G01X383163Y297663D02*
X430684D01*
G01X382000Y296500D02*
X383163Y297663D01*
G01X369184Y265394D02*
X364815D01*
G01X369185Y265393D02*
X369184Y265394D01*
G01X413966Y265393D02*
X369185D01*
G01X361500Y289637D02*
X377863Y306000D01*
G01X361500Y284796D02*
Y289637D01*
G01X338954Y262250D02*
X361500Y284796D01*
G01X338733Y262250D02*
X338954D01*
G01X335800Y259317D02*
X338733Y262250D01*
G01X335800Y249780D02*
Y259317D01*
G01X386650Y257950D02*
X402270D01*
G01X378600Y249900D02*
X386650Y257950D01*
G01X365506Y249900D02*
X378600D01*
G01X384408Y287400D02*
X380400D01*
G01X386200Y289192D02*
X384408Y287400D01*
G01X421571Y289192D02*
X386200D01*
G01X359500Y290466D02*
X377534Y308500D01*
G01X359500Y285625D02*
Y290466D01*
G01X342374Y268499D02*
X359500Y285625D01*
G01X336780Y268499D02*
X342374D01*
G01X331300Y263019D02*
X336780Y268499D01*
G01X331300Y248109D02*
Y263019D01*
G01X362478Y269267D02*
X414029D01*
G01X382112Y273862D02*
X430393D01*
G01X380850Y272600D02*
X382112Y273862D01*
G01X379000Y272600D02*
X380850D01*
G01X380829Y263393D02*
X365643D01*
G01X381829Y264393D02*
X380829Y263393D01*
G01X411029Y264393D02*
X381829D01*
G01X351000Y282783D02*
Y314217D01*
G01X341703Y273486D02*
X351000Y282783D01*
G01X331236Y273486D02*
X341703D01*
G01X363879Y281635D02*
X427303D01*
G01X338100Y255856D02*
X363879Y281635D01*
G01X338100Y249251D02*
Y255856D01*
G01X384600Y285600D02*
X421202D01*
G01X337732Y283582D02*
Y315036D01*
G01X377401Y255001D02*
X361231D01*
G01X385793Y263393D02*
X377401Y255001D01*
G01X408092Y263393D02*
X385793D01*
G01X386300Y293100D02*
X384300Y291100D01*
G01X426100Y293100D02*
X386300D01*
G01X382949Y331470D02*
X416562D01*
G01X380829Y329350D02*
X382949Y331470D01*
G01X342350Y329350D02*
X380829D01*
G01X331214Y318214D02*
X342350Y329350D01*
G01X331214Y316182D02*
Y318214D01*
G01X330032Y315000D02*
X331214Y316182D01*
G01X330032Y310778D02*
Y315000D01*
G01X386061Y305396D02*
X385887Y305222D01*
G01X422951Y305396D02*
X386061D01*
G01X384450Y311950D02*
X378155D01*
G01X389527Y317027D02*
X384450Y311950D01*
G01X385620Y341668D02*
X400332D01*
G01X379688Y347600D02*
X385620Y341668D01*
G01X374250Y347600D02*
X379688D01*
G01X369500Y342850D02*
X374250Y347600D01*
G01X343467Y342850D02*
X369500D01*
G01X327867Y327250D02*
X343467Y342850D01*
G01X384728Y358023D02*
X336771D01*
G01X392827Y349924D02*
X384728Y358023D01*
G01X383080Y355235D02*
X336812D01*
G01X390391Y347924D02*
X383080Y355235D01*
G01X386249Y360051D02*
X394376Y351924D01*
G01X332051Y360051D02*
X386249D01*
G01X382406Y301600D02*
X430684D01*
G01X381396Y302610D02*
X382406Y301600D01*
G01X384097Y330470D02*
X415818D01*
G01X380977Y327350D02*
X384097Y330470D01*
G01X343179Y327350D02*
X380977D01*
G01X333214Y317385D02*
X343179Y327350D01*
G01X333214Y315353D02*
Y317385D01*
G01X332032Y314171D02*
X333214Y315353D01*
G01X332032Y309949D02*
Y314171D01*
G01X325729Y303646D02*
X332032Y309949D01*
G01X335214Y314524D02*
X334032Y313342D01*
G01X335214Y315347D02*
Y314524D01*
G01X341767Y321900D02*
X335214Y315347D01*
G01X380152Y321900D02*
X341767D01*
G01X386722Y328470D02*
X380152Y321900D01*
G01X409944Y328470D02*
X386722D01*
G01X366350Y339500D02*
X364050Y337200D01*
G01X398500Y339500D02*
X366350D01*
G01X361250Y334400D02*
X364050Y337200D01*
G01X341369Y334400D02*
X361250D01*
G01X325514Y318545D02*
X341369Y334400D01*
G01X325514Y314839D02*
Y318545D01*
G01X386448Y320448D02*
X411552D01*
G01X379950Y313950D02*
X386448Y320448D01*
G01X361050Y313950D02*
X379950D01*
G01X359200Y315800D02*
X361050Y313950D01*
G01X386637Y308637D02*
X419711D01*
G01X384000Y306000D02*
X386637Y308637D01*
G01X377863Y306000D02*
X384000D01*
G01X385000Y308500D02*
X389313Y312813D01*
G01X377534Y308500D02*
X385000D01*
G01X379988Y323900D02*
X360300D01*
G01X385558Y329470D02*
X379988Y323900D01*
G01X412881Y329470D02*
X385558D01*
G01X380893Y350274D02*
X387243Y343924D01*
G01X348818Y350274D02*
X380893D01*
G01X346467Y347923D02*
X348818Y350274D01*
G01X339606Y347923D02*
X346467D01*
G01X331850Y346467D02*
Y344433D01*
G01X337830Y352447D02*
X331850Y346467D01*
G01X382573Y352447D02*
X337830D01*
G01X389096Y345924D02*
X382573Y352447D01*
G01X381988Y317900D02*
X388473Y324385D01*
G01X354683Y317900D02*
X381988D01*
G01X351000Y314217D02*
X354683Y317900D01*
G01X381780Y319900D02*
X388360Y326480D01*
G01X342596Y319900D02*
X381780D01*
G01X337732Y315036D02*
X342596Y319900D01*
G01X375175Y415676D02*
X404804Y386047D01*
G01X386137Y393398D02*
X401488Y378047D01*
G01X403975Y384047D02*
X375011Y413011D01*
G01X406696Y390047D02*
X373893Y422850D01*
G01X374722Y424850D02*
X407525Y392047D01*
G01X402317Y380047D02*
X386879Y395485D01*
G01X385672Y374060D02*
X395685Y364047D01*
G01X387136Y362839D02*
X325666D01*
G01X386280Y367794D02*
X325277D01*
G01X394150Y359924D02*
X386280Y367794D01*
G01X405867Y388047D02*
X375914Y418000D01*
G01X396514Y366047D02*
X386501Y376060D01*
G01X375551Y426850D02*
X408354Y394047D01*
G01X385308Y391398D02*
X400659Y376047D01*
G01X417322Y233764D02*
Y236221D01*
G01X413308Y229750D02*
X417322Y233764D01*
G01X412449Y229750D02*
X413308D01*
G01X405503Y222804D02*
X412449Y229750D01*
G01X389304Y222804D02*
X405503D01*
G01X400025Y234671D02*
X401575Y236221D01*
G01X390942Y234671D02*
X400025D01*
G01X405512Y235412D02*
Y236221D01*
G01X403708Y233608D02*
X405512Y235412D01*
G01X403708Y232224D02*
Y233608D01*
G01X402065Y230581D02*
X403708Y232224D01*
G01X389681Y230581D02*
X402065D01*
G01X418873Y233074D02*
Y242545D01*
G01X411368Y225569D02*
X418873Y233074D01*
G01X411368Y216107D02*
Y225569D01*
G01X410112Y214851D02*
X411368Y216107D01*
G01X393760Y214851D02*
X410112D01*
G01X392138Y213229D02*
X393760Y214851D01*
G01X392138Y212625D02*
Y213229D01*
G01X390388Y210875D02*
X392138Y212625D01*
G01X389784Y210875D02*
X390388D01*
G01X422810Y227704D02*
Y246482D01*
G01X421462Y226356D02*
X422810Y227704D01*
G01X417076Y226356D02*
X421462D01*
G01X415455Y224735D02*
X417076Y226356D01*
G01X415455Y212475D02*
Y224735D01*
G01X414029Y211049D02*
X415455Y212475D01*
G01X397677Y211049D02*
X414029D01*
G01X395480Y208852D02*
X397677Y211049D01*
G01X395480Y208248D02*
Y208852D01*
G01X393858Y206626D02*
X395480Y208248D01*
G01X393254Y206626D02*
X393858D01*
G01X391938Y205310D02*
X393254Y206626D01*
G01X391938Y202243D02*
Y205310D01*
G01X411579Y236479D02*
X413387Y238287D01*
G01X411579Y232221D02*
Y236479D01*
G01X406155Y226797D02*
X411579Y232221D01*
G01X389797Y226797D02*
X406155D01*
G01X403944Y245663D02*
X405512Y244095D01*
G01X403944Y251344D02*
Y245663D01*
G01X401138Y254150D02*
X403944Y251344D01*
G01X430684Y301600D02*
X433071Y299213D01*
G01X418873Y242545D02*
X417323Y244095D01*
G01X407830Y253588D02*
X413386Y248032D01*
G01X407830Y259718D02*
Y253588D01*
G01X405155Y262393D02*
X407830Y259718D01*
G01X388264Y262393D02*
X405155D01*
G01X430684Y297663D02*
X433071Y295276D01*
G01X400152Y249455D02*
X388055D01*
G01X401575Y248032D02*
X400152Y249455D01*
G01X418873Y260486D02*
X413966Y265393D01*
G01X418873Y254356D02*
Y260486D01*
G01X421260Y251969D02*
X418873Y254356D01*
G01X405512Y253510D02*
Y248032D01*
G01X403620Y255402D02*
X405512Y253510D01*
G01X403620Y256600D02*
Y255402D01*
G01X402270Y257950D02*
X403620Y256600D01*
G01X422810Y246482D02*
X421260Y248032D01*
G01X423718Y291339D02*
X421571Y289192D01*
G01X425197Y291339D02*
X423718D01*
G01X435400Y298628D02*
Y306951D01*
G01X437027Y297001D02*
X435400Y298628D01*
G01X442500Y297001D02*
X437027D01*
G01X445775Y293726D02*
X442500Y297001D01*
G01X466476Y293726D02*
X445775D01*
G01X419091Y249800D02*
X417323Y248032D01*
G01X421284Y249800D02*
X419091D01*
G01X422810Y251326D02*
X421284Y249800D01*
G01X422810Y260486D02*
Y251326D01*
G01X421903Y261393D02*
X422810Y260486D01*
G01X421454Y261393D02*
X421903D01*
G01X414936Y267911D02*
X421454Y261393D01*
G01X414936Y268360D02*
Y267911D01*
G01X414029Y269267D02*
X414936Y268360D01*
G01X435105Y285500D02*
X437007Y287402D01*
G01X432700Y285500D02*
X435105D01*
G01X431080Y283880D02*
X432700Y285500D01*
G01X431080Y274549D02*
Y283880D01*
G01X430393Y273862D02*
X431080Y274549D01*
G01X400025Y241708D02*
X388795D01*
G01X401575Y240158D02*
X400025Y241708D01*
G01Y245645D02*
X389903D01*
G01X401575Y244095D02*
X400025Y245645D01*
G01X400214Y247200D02*
X388629D01*
G01X400932Y246482D02*
X400214Y247200D01*
G01X401381Y246482D02*
X400932D01*
G01X403962Y243901D02*
X401381Y246482D01*
G01X403962Y243452D02*
Y243901D01*
G01X404869Y242545D02*
X403962Y243452D01*
G01X411836Y242545D02*
X404869D01*
G01X413386Y244095D02*
X411836Y242545D01*
G01X403954Y238600D02*
X405512Y240158D01*
G01X388516Y238600D02*
X403954D01*
G01X415124Y260298D02*
X411029Y264393D01*
G01X415124Y254168D02*
Y260298D01*
G01X417323Y251969D02*
X415124Y254168D01*
G01X427303Y281635D02*
X433070Y287402D01*
G01X431327Y291339D02*
X433071D01*
G01X429139Y289151D02*
X431327Y291339D01*
G01X424753Y289151D02*
X429139D01*
G01X421202Y285600D02*
X424753Y289151D01*
G01X411149Y260336D02*
X408092Y263393D01*
G01X411149Y254206D02*
Y260336D01*
G01X413386Y251969D02*
X411149Y254206D01*
G01X413387Y238287D02*
Y240158D01*
G01X427860Y291340D02*
X426100Y293100D01*
G01X429134Y291340D02*
X427860D01*
G01X416562Y331470D02*
X421260Y326772D01*
G01X425197Y303150D02*
X422951Y305396D01*
G01X411321Y317027D02*
X389527D01*
G01X413386Y314962D02*
X411321Y317027D01*
G01X445525Y324385D02*
X451866Y318044D01*
G01X431415Y324385D02*
X445525D01*
G01X420250Y335550D02*
X431415Y324385D01*
G01X406450Y335550D02*
X420250D01*
G01X400332Y341668D02*
X406450Y335550D01*
G01X419500Y349924D02*
X392827D01*
G01X426574Y342850D02*
X419500Y349924D01*
G01X431002Y342850D02*
X426574D01*
G01X438755Y335097D02*
X431002Y342850D01*
G01X452537Y335097D02*
X438755D01*
G01X448509Y333212D02*
X462180Y319541D01*
G01X434788Y333212D02*
X448509D01*
G01X427500Y340500D02*
X434788Y333212D01*
G01X425500Y340500D02*
X427500D01*
G01X420933Y345067D02*
X425500Y340500D01*
G01X408013Y345067D02*
X420933D01*
G01X405921Y347159D02*
X408013Y345067D01*
G01X405156Y347924D02*
X390391D01*
G01X405921Y347159D02*
X405156Y347924D01*
G01X425618Y351924D02*
X430464Y347078D01*
G01X394376Y351924D02*
X425618D01*
G01X434692Y342850D02*
X453817D01*
G01X430464Y347078D02*
X434692Y342850D01*
G01X421259Y324474D02*
Y322835D01*
G01X418883Y326850D02*
X421259Y324474D01*
G01X418883Y327405D02*
Y326850D01*
G01X415818Y330470D02*
X418883Y327405D01*
G01X411772Y326642D02*
X409944Y328470D01*
G01X411772Y326193D02*
Y326642D01*
G01X415130Y322835D02*
X411772Y326193D01*
G01X417322Y322835D02*
X415130D01*
G01X393773Y356202D02*
X387136Y362839D01*
G01X446420Y356202D02*
X393773D01*
G01X457971Y344651D02*
X446420Y356202D01*
G01X399500Y338500D02*
X398500Y339500D01*
G01X399500Y336500D02*
Y338500D01*
G01X402450Y333550D02*
X399500Y336500D01*
G01X419420Y333550D02*
X402450D01*
G01X430953Y322017D02*
X419420Y333550D01*
G01X430953Y318609D02*
Y322017D01*
G01X432337Y317225D02*
X430953Y318609D01*
G01X444362Y317225D02*
X432337D01*
G01X445076Y316511D02*
X444362Y317225D01*
G01X445525Y316511D02*
X445076D01*
G01X446432Y315604D02*
X445525Y316511D01*
G01X446432Y315155D02*
Y315604D01*
G01X449013Y312574D02*
X446432Y315155D01*
G01X426848Y309373D02*
X433071Y303150D01*
G01X424655Y309373D02*
X426848D01*
G01X423301Y310727D02*
X424655Y309373D01*
G01X423301Y315113D02*
Y310727D01*
G01X421620Y316794D02*
X423301Y315113D01*
G01X415206Y316794D02*
X421620D01*
G01X411552Y320448D02*
X415206Y316794D01*
G01X419711Y308637D02*
X421260Y307088D01*
G01X446390Y359924D02*
X394150D01*
G01X456904Y349410D02*
X446390Y359924D01*
G01X448625Y317348D02*
X455143Y310830D01*
G01X448176Y317348D02*
X448625D01*
G01X447269Y318255D02*
X448176Y317348D01*
G01X447269Y318704D02*
Y318255D01*
G01X445394Y320579D02*
X447269Y318704D01*
G01X433806Y320579D02*
X445394D01*
G01X419835Y334550D02*
X433806Y320579D01*
G01X404600Y334550D02*
X419835D01*
G01X401800Y337350D02*
X404600Y334550D01*
G01X401700Y337350D02*
X401800D01*
G01X419112Y312813D02*
X421260Y314961D01*
G01X389313Y312813D02*
X419112D01*
G01X397508Y332550D02*
X392959Y337099D01*
G01X417675Y332550D02*
X397508D01*
G01X427200Y323025D02*
X417675Y332550D01*
G01X427200Y318639D02*
Y323025D01*
G01X428491Y317348D02*
X427200Y318639D01*
G01X428940Y317348D02*
X428491D01*
G01X430684Y315604D02*
X428940Y317348D01*
G01X430684Y315155D02*
Y315604D01*
G01X433265Y312574D02*
X430684Y315155D01*
G01X433714Y312574D02*
X433265D01*
G01X434621Y311667D02*
X433714Y312574D01*
G01X434621Y311218D02*
Y311667D01*
G01X437202Y308637D02*
X434621Y311218D01*
G01X437651Y308637D02*
X437202D01*
G01X439395Y306893D02*
X437651Y308637D01*
G01X439395Y302507D02*
Y306893D01*
G01X440302Y301600D02*
X439395Y302507D01*
G01X450370Y301600D02*
X440302D01*
G01X415773Y326578D02*
X412881Y329470D01*
G01X415773Y326129D02*
Y326578D01*
G01X416680Y325222D02*
X415773Y326129D01*
G01X417128Y325222D02*
X416680D01*
G01X419385Y322965D02*
X417128Y325222D01*
G01X419385Y322516D02*
Y322965D01*
G01X420761Y321140D02*
X419385Y322516D01*
G01X421211Y321140D02*
X420761D01*
G01X423100Y319251D02*
X421211Y321140D01*
G01X423100Y318802D02*
Y319251D01*
G01X424554Y317348D02*
X423100Y318802D01*
G01X425003Y317348D02*
X424554D01*
G01X427584Y314767D02*
X425003Y317348D01*
G01X427584Y314318D02*
Y314767D01*
G01X428491Y313411D02*
X427584Y314318D01*
G01X428940Y313411D02*
X428491D01*
G01X431521Y310830D02*
X428940Y313411D01*
G01X431521Y310381D02*
Y310830D01*
G01X432428Y309474D02*
X431521Y310381D01*
G01X432877Y309474D02*
X432428D01*
G01X435400Y306951D02*
X432877Y309474D01*
G01X401177Y343924D02*
X405783Y339318D01*
G01X387243Y343924D02*
X401177D01*
G01X402148Y345924D02*
X389096D01*
G01X405022Y343050D02*
X402148Y345924D01*
G01X419050Y343050D02*
X405022D01*
G01X428500Y333600D02*
X419050Y343050D01*
G01X432201Y333600D02*
X428500D01*
G01X433951Y331850D02*
X432201Y333600D01*
G01X445934Y331850D02*
X433951D01*
G01X458243Y319541D02*
X445934Y331850D01*
G01X420074Y318898D02*
X421260D01*
G01X418176Y320796D02*
X420074Y318898D01*
G01X414404Y320796D02*
X418176D01*
G01X410815Y324385D02*
X414404Y320796D01*
G01X388473Y324385D02*
X410815D01*
G01X448387Y362047D02*
X459024Y351410D01*
G01X390210Y326480D02*
X390550Y326820D01*
G01X388360Y326480D02*
X390210D01*
G01X397343Y368047D02*
X387330Y378060D01*
G01X457303Y368047D02*
X397343D01*
G01X404804Y386047D02*
X485757D01*
G01X401488Y378047D02*
X475797D01*
G01X399001Y372047D02*
X462215D01*
G01X388988Y382060D02*
X399001Y372047D01*
G01X484928Y384047D02*
X403975D01*
G01X403146Y382047D02*
X484099D01*
G01X387708Y397485D02*
X403146Y382047D01*
G01X488237Y390047D02*
X406696D01*
G01X407525Y392047D02*
X478679D01*
G01X483270Y380047D02*
X402317D01*
G01X446000Y421000D02*
X455469D01*
G01X445000Y422000D02*
X446000Y421000D01*
G01X395685Y364047D02*
X450380D01*
G01X487408Y388047D02*
X405867D01*
G01X452436Y366047D02*
X396514D01*
G01X408354Y394047D02*
X477850D01*
G01X399830Y374047D02*
X389577Y384300D01*
G01X466362Y374047D02*
X399830D01*
G01X398172Y370047D02*
X459652D01*
G01X388159Y380060D02*
X398172Y370047D01*
G01X400659Y376047D02*
X472478D01*
G01X394856Y362047D02*
X448387D01*
G01X387109Y369794D02*
X394856Y362047D01*
G01X466889Y291339D02*
X460630D01*
G01X468700Y293150D02*
X466889Y291339D01*
G01X474968Y293150D02*
X468700D01*
G01X479150Y297332D02*
X474968Y293150D01*
G01X512659Y297332D02*
X479150D01*
G01X456694Y295276D02*
X450370Y301600D01*
G01X470400Y297650D02*
X466476Y293726D01*
G01X475977Y297650D02*
X470400D01*
G01X479200Y300873D02*
X475977Y297650D01*
G01X466000Y359350D02*
X457303Y368047D01*
G01X475184Y359350D02*
X466000D01*
G01X498034Y336500D02*
X475184Y359350D01*
G01X535059Y336500D02*
X498034D01*
G01X505645Y346500D02*
X526874D01*
G01X503988Y348157D02*
X505645Y346500D01*
G01X503988Y349267D02*
Y348157D01*
G01X495050Y358205D02*
X503988Y349267D01*
G01X495050Y359976D02*
Y358205D01*
G01X492450Y362576D02*
X495050Y359976D01*
G01X464567Y304895D02*
Y303151D01*
G01X463017Y306445D02*
X464567Y304895D01*
G01X463017Y306483D02*
Y306445D01*
G01X462900Y306600D02*
X463017Y306483D01*
G01X462900Y307370D02*
Y306600D01*
G01X461300Y308970D02*
X462900Y307370D01*
G01X460491Y308970D02*
X461300D01*
G01X459080Y310381D02*
X460491Y308970D01*
G01X459080Y310830D02*
Y310381D01*
G01X456693Y313217D02*
X459080Y310830D01*
G01X456244Y313217D02*
X456693D01*
G01X451866Y317595D02*
X456244Y313217D01*
G01X451866Y318044D02*
Y317595D01*
G01X499692Y340500D02*
X529361D01*
G01X474790Y365402D02*
X499692Y340500D01*
G01X454250Y333384D02*
X452537Y335097D01*
G01X454250Y332606D02*
Y333384D01*
G01X464567Y322289D02*
X454250Y332606D01*
G01X464567Y318898D02*
Y322289D01*
G01X505492Y361300D02*
X504200Y362592D01*
G01X508900Y361300D02*
X505492D01*
G01X517604Y352596D02*
X508900Y361300D01*
G01X466224Y309369D02*
X468505Y307088D01*
G01X466224Y315048D02*
Y309369D01*
G01X462180Y319092D02*
X466224Y315048D01*
G01X462180Y319541D02*
Y319092D01*
G01X462282Y335395D02*
X470473Y327204D01*
G01X460098Y335395D02*
X462282D01*
G01X458583Y336910D02*
X460098Y335395D01*
G01X458583Y338084D02*
Y336910D01*
G01X453817Y342850D02*
X458583Y338084D01*
G01X509995Y348643D02*
X510138Y348500D01*
G01X509995Y348918D02*
Y348643D01*
G01X502550Y356363D02*
X509995Y348918D01*
G01X502550Y361413D02*
Y356363D01*
G01X502200Y361763D02*
X502550Y361413D01*
G01X507517Y329322D02*
X519027Y317812D01*
G01X487326Y329322D02*
X507517D01*
G01X480324Y336324D02*
X487326Y329322D01*
G01X478334Y336324D02*
X480324D01*
G01X468500Y346158D02*
X478334Y336324D01*
G01X468500Y347500D02*
Y346158D01*
G01X498233Y361059D02*
X497000Y362292D01*
G01X499467Y361059D02*
X498233D01*
G01X500550Y359976D02*
X499467Y361059D01*
G01X500550Y355534D02*
Y359976D01*
G01X506368Y349716D02*
X500550Y355534D01*
G01X506368Y348606D02*
Y349716D01*
G01X506262Y348500D02*
X506368Y348606D01*
G01X495202Y333499D02*
X513263D01*
G01X484111Y344587D02*
X495202Y333499D01*
G01X481816Y344587D02*
X484111D01*
G01X479509Y346894D02*
X481816Y344587D01*
G01X479509Y349367D02*
Y346894D01*
G01X475466Y353410D02*
X479509Y349367D01*
G01X461017Y353410D02*
X475466D01*
G01X450380Y364047D02*
X461017Y353410D01*
G01X466449Y344651D02*
X457971D01*
G01X476200Y334900D02*
X466449Y344651D01*
G01X449462Y312574D02*
X449013D01*
G01X450369Y311667D02*
X449462Y312574D01*
G01X450369Y311218D02*
Y311667D01*
G01X452594Y308993D02*
X450369Y311218D01*
G01X453219Y308993D02*
X452594D01*
G01X454437Y307775D02*
X453219Y308993D01*
G01X454437Y307150D02*
Y307775D01*
G01X456887Y304700D02*
X454437Y307150D01*
G01X457336Y304700D02*
X456887D01*
G01X458886Y303150D02*
X457336Y304700D01*
G01X460630Y303150D02*
X458886D01*
G01X469207Y349410D02*
X456904D01*
G01X479226Y339391D02*
X469207Y349410D01*
G01X481879Y339391D02*
X479226D01*
G01X490770Y330500D02*
X481879Y339391D01*
G01X511400Y330500D02*
X490770D01*
G01X463073Y355410D02*
X452436Y366047D01*
G01X476295Y355410D02*
X463073D01*
G01X496905Y334800D02*
X476295Y355410D01*
G01X514335Y334800D02*
X496905D01*
G01X466954Y301601D02*
X468504Y303151D01*
G01X463924Y301601D02*
X466954D01*
G01X462300Y303225D02*
X463924Y301601D01*
G01X462300Y303673D02*
Y303225D01*
G01X460436Y305537D02*
X462300Y303673D01*
G01X459987Y305537D02*
X460436D01*
G01X459080Y306444D02*
X459987Y305537D01*
G01X459080Y306893D02*
Y306444D01*
G01X456499Y309474D02*
X459080Y306893D01*
G01X456050Y309474D02*
X456499D01*
G01X455143Y310381D02*
X456050Y309474D01*
G01X455143Y310830D02*
Y310381D01*
G01X522914Y300873D02*
X479200D01*
G01X479483Y309383D02*
X517233D01*
G01X475500Y305400D02*
X479483Y309383D01*
G01X466255Y305400D02*
X475500D01*
G01X464567Y307088D02*
X466255Y305400D01*
G01X458243Y319092D02*
Y319541D01*
G01X460651Y316684D02*
X458243Y319092D01*
G01X461100Y316684D02*
X460651D01*
G01X464567Y313217D02*
X461100Y316684D01*
G01X464567Y311025D02*
Y313217D01*
G01X501521Y342500D02*
X476050Y367971D01*
G01X528532Y342500D02*
X501521D01*
G01X498863Y338500D02*
X530190D01*
G01X474163Y363200D02*
X498863Y338500D01*
G01X503521Y344500D02*
X527703D01*
G01X499988Y348033D02*
X503521Y344500D01*
G01X499988Y349267D02*
Y348033D01*
G01X498905Y350350D02*
X499988Y349267D01*
G01X497869Y350350D02*
X498905D01*
G01X486950Y361269D02*
X497869Y350350D01*
G01X486950Y367850D02*
Y361269D01*
G01X493291Y332358D02*
X511942D01*
G01X483277Y342369D02*
X493291Y332358D01*
G01X479077Y342369D02*
X483277D01*
G01X470036Y351410D02*
X479077Y342369D01*
G01X459024Y351410D02*
X470036D01*
G01X510967Y365059D02*
X521336Y354690D01*
G01X506967Y365059D02*
X510967D01*
G01X506818Y365208D02*
X506967Y365059D01*
G01X505992Y365208D02*
X506818D01*
G01X504700Y366500D02*
X505992Y365208D01*
G01X504700Y370323D02*
Y366500D01*
G01X501523Y373500D02*
X504700Y370323D01*
G01X498304Y373500D02*
X501523D01*
G01X485757Y386047D02*
X498304Y373500D01*
G01X492450Y366976D02*
Y362576D01*
G01X490226Y369200D02*
X492450Y366976D01*
G01X488600Y369200D02*
X490226D01*
G01X486828Y370972D02*
X488600Y369200D01*
G01X482872Y370972D02*
X486828D01*
G01X475797Y378047D02*
X482872Y370972D01*
G01X472268Y365402D02*
X474790D01*
G01X470433Y367237D02*
X472268Y365402D01*
G01X467025Y367237D02*
X470433D01*
G01X462215Y372047D02*
X467025Y367237D01*
G01X500350Y368625D02*
X484928Y384047D01*
G01X500350Y367950D02*
Y368625D01*
G01X504200Y364100D02*
X500350Y367950D01*
G01X504200Y362592D02*
Y364100D01*
G01X502200Y363271D02*
Y361763D01*
G01X498350Y367121D02*
X502200Y363271D01*
G01X498350Y367796D02*
Y367121D01*
G01X484099Y382047D02*
X498350Y367796D01*
G01X495102Y383182D02*
X488237Y390047D01*
G01X497499Y383182D02*
X495102D01*
G01X510700Y369981D02*
X497499Y383182D01*
G01X510700Y367309D02*
Y369981D01*
G01X509190Y384881D02*
X533709D01*
G01X506721Y387350D02*
X509190Y384881D01*
G01X493763Y387350D02*
X506721D01*
G01X489066Y392047D02*
X493763Y387350D01*
G01X488627Y392047D02*
X489066D01*
G01X488626Y392048D02*
X488627Y392047D01*
G01X478680Y392048D02*
X488626D01*
G01X478679Y392047D02*
X478680Y392048D01*
G01X496200Y367117D02*
X483270Y380047D01*
G01X496200Y365497D02*
Y367117D01*
G01X497000Y364697D02*
X496200Y365497D01*
G01X497000Y362292D02*
Y364697D01*
G01X455469Y421000D02*
X485269Y450800D01*
G01X494670Y380785D02*
X487408Y388047D01*
G01X497067Y380785D02*
X494670D01*
G01X506700Y371152D02*
X497067Y380785D01*
G01X506700Y367309D02*
Y371152D01*
G01X510019Y386881D02*
X534304D01*
G01X507550Y389350D02*
X510019Y386881D01*
G01X495750Y389350D02*
X507550D01*
G01X491052Y394048D02*
X495750Y389350D01*
G01X477851Y394048D02*
X491052D01*
G01X477850Y394047D02*
X477851Y394048D01*
G01X471059Y369350D02*
X466362Y374047D01*
G01X474967Y369350D02*
X471059D01*
G01X476050Y368267D02*
X474967Y369350D01*
G01X476050Y367971D02*
Y368267D01*
G01X471259Y363200D02*
X474163D01*
G01X469540Y364919D02*
X471259Y363200D01*
G01X464780Y364919D02*
X469540D01*
G01X459652Y370047D02*
X464780Y364919D01*
G01X485900Y368900D02*
X486950Y367850D01*
G01X479624Y368900D02*
X485900D01*
G01X478644Y369880D02*
X479624Y368900D01*
G01X472478Y376047D02*
X478644Y369880D01*
G01X500670Y454570D02*
X555210D01*
G01X496900Y450800D02*
X500670Y454570D01*
G01X485269Y450800D02*
X496900D01*
G01X514095Y298768D02*
X512659Y297332D01*
G01X522021Y298768D02*
X514095D01*
G01X532208Y288581D02*
X522021Y298768D01*
G01X557096Y288581D02*
X532208D01*
G01X591989Y253688D02*
X557096Y288581D01*
G01X557582Y296735D02*
X606153Y248164D01*
G01X534251Y296735D02*
X557582D01*
G01X519027Y311959D02*
X534251Y296735D01*
G01X533147Y290640D02*
X522914Y300873D01*
G01X557866Y290640D02*
X533147D01*
G01X593989Y254517D02*
X557866Y290640D01*
G01X556745Y294590D02*
X596200Y255135D01*
G01X532026Y294590D02*
X556745D01*
G01X517233Y309383D02*
X532026Y294590D01*
G01X538892Y340333D02*
X535059Y336500D01*
G01X541129Y340333D02*
X538892D01*
G01X541933Y339529D02*
X541129Y340333D01*
G01X541933Y334549D02*
Y339529D01*
G01X539828Y332444D02*
X541933Y334549D01*
G01X539828Y332310D02*
Y332444D01*
G01X538436Y330918D02*
X539828Y332310D01*
G01X550056Y338039D02*
X554685Y333410D01*
G01X550056Y342899D02*
Y338039D01*
G01X546655Y346300D02*
X550056Y342899D01*
G01X545483Y346300D02*
X546655D01*
G01X544100Y347683D02*
X545483Y346300D01*
G01X544100Y350058D02*
Y347683D01*
G01X539468Y354690D02*
X544100Y350058D01*
G01X521336Y354690D02*
X539468D01*
G01X538200Y350300D02*
X540200Y348300D01*
G01X530674Y350300D02*
X538200D01*
G01X526874Y346500D02*
X530674Y350300D01*
G01X537533Y344260D02*
X539446Y342347D01*
G01X533121Y344260D02*
X537533D01*
G01X529361Y340500D02*
X533121Y344260D01*
G01X538733Y352596D02*
X517604D01*
G01X542100Y349229D02*
X538733Y352596D01*
G01X542100Y346854D02*
Y349229D01*
G01X544654Y344300D02*
X542100Y346854D01*
G01X545826Y344300D02*
X544654D01*
G01X547927Y342199D02*
X545826Y344300D01*
G01X519027Y317812D02*
Y311959D01*
G01X546100Y353719D02*
Y348300D01*
G01X544630Y355189D02*
X546100Y353719D01*
G01X544630Y375469D02*
Y355189D01*
G01X518862Y329681D02*
X519629Y330448D01*
G01X517081Y329681D02*
X518862D01*
G01X513263Y333499D02*
X517081Y329681D01*
G01X516458Y325442D02*
X511400Y330500D01*
G01X522241Y325442D02*
X516458D01*
G01X529265Y332466D02*
X522241Y325442D01*
G01X536577Y332466D02*
X529265D01*
G01X538476Y334365D02*
X536577Y332466D01*
G01X516005Y333130D02*
X514335Y334800D01*
G01X521691Y333130D02*
X516005D01*
G01X521914Y332907D02*
X521691Y333130D01*
G01X550100Y370907D02*
Y348300D01*
G01X532292Y346260D02*
X528532Y342500D01*
G01X538362Y346260D02*
X532292D01*
G01X542275Y342347D02*
X538362Y346260D01*
G01X543646Y342347D02*
X542275D01*
G01X530190Y338500D02*
X534100Y342410D01*
G01X531503Y348300D02*
X536200D01*
G01X527703Y344500D02*
X531503Y348300D01*
G01X517208Y327092D02*
X519263D01*
G01X511942Y332358D02*
X517208Y327092D01*
G01X538012Y382087D02*
X544630Y375469D01*
G01X537195Y382618D02*
X538012Y382087D01*
G01X537194Y382618D02*
X537195D01*
G01X533709Y384881D02*
X537194Y382618D01*
G01X547603Y373404D02*
X550100Y370907D01*
G01X547603Y374794D02*
Y373404D01*
G01X546631Y376290D02*
X547603Y374794D01*
G01X546618Y376309D02*
X546631Y376290D01*
G01X546617Y376311D02*
X546618Y376309D01*
G01X539278Y383650D02*
X546617Y376311D01*
G01X538359Y384248D02*
X539278Y383650D01*
G01X538357Y384249D02*
X538359Y384248D01*
G01X534304Y386881D02*
X538357Y384249D01*
G01X562930Y462290D02*
X589740D01*
G01X555210Y454570D02*
X562930Y462290D01*
G01X610895Y23932D02*
Y122160D01*
G01X621727Y13100D02*
X610895Y23932D01*
G01X638103Y13100D02*
X621727D01*
G01X620222Y26617D02*
X627500Y19339D01*
G01X620222Y125570D02*
Y26617D01*
G01X613782Y25545D02*
Y123202D01*
G01X624211Y15116D02*
X613782Y25545D01*
G01X638961Y15116D02*
X624211D01*
G01X625924Y17142D02*
X639764D01*
G01X616860Y26206D02*
X625924Y17142D01*
G01X616860Y124877D02*
Y26206D01*
G01X595607Y162340D02*
Y223573D01*
G01X601621Y156326D02*
X595607Y162340D01*
G01X601621Y131434D02*
Y156326D01*
G01X610895Y122160D02*
X601621Y131434D01*
G01X612173Y133619D02*
X620222Y125570D01*
G01X612173Y160300D02*
Y133619D01*
G01X606153Y166320D02*
X612173Y160300D01*
G01X606153Y248164D02*
Y166320D01*
G01X599381Y163016D02*
Y223448D01*
G01X604952Y157445D02*
X599381Y163016D01*
G01X604952Y132032D02*
Y157445D01*
G01X613782Y123202D02*
X604952Y132032D01*
G01X608371Y133366D02*
X616860Y124877D01*
G01X608371Y158911D02*
Y133366D01*
G01X602788Y164494D02*
X608371Y158911D01*
G01X602788Y224112D02*
Y164494D01*
G01X591989Y227191D02*
Y253688D01*
G01X595607Y223573D02*
X591989Y227191D01*
G01X593989Y228840D02*
Y254517D01*
G01X599381Y223448D02*
X593989Y228840D01*
G01X596200Y230700D02*
X602788Y224112D01*
G01X596200Y255135D02*
Y230700D01*
G01X598500Y471050D02*
X640570D01*
G01X589740Y462290D02*
X598500Y471050D01*
G01X642124Y11953D02*
X638961Y15116D01*
G01X645092Y11953D02*
X642124D01*
G01X647103Y13964D02*
X645092Y11953D01*
G01X639764Y17142D02*
X643103Y13803D01*
G01X689749Y417915D02*
X746127D01*
G01X680452Y408618D02*
X689749Y417915D01*
G01X680452Y385052D02*
Y408618D01*
G01X680300Y384900D02*
X680452Y385052D01*
G01X677007Y437813D02*
X683250D01*
G01X671290Y443530D02*
X677007Y437813D01*
G01X668090Y443530D02*
X671290D01*
G01X640570Y471050D02*
X668090Y443530D01*
G01X748349Y173115D02*
X741952D01*
G01X768898Y193664D02*
X748349Y173115D01*
G01X745375Y187115D02*
X743752D01*
G01X754645Y196385D02*
X745375Y187115D01*
G01X754645Y206193D02*
Y196385D01*
G01X756839Y208387D02*
X754645Y206193D01*
G01X756839Y212975D02*
Y208387D01*
G01X768219Y224355D02*
X756839Y212975D01*
G01X714173Y207346D02*
Y201574D01*
G01X704708Y216811D02*
X714173Y207346D01*
G01X704708Y252647D02*
Y216811D01*
G01X750839Y221200D02*
X759558Y229919D01*
G01X750839Y210874D02*
Y221200D01*
G01X748645Y208680D02*
X750839Y210874D01*
G01X748645Y200833D02*
Y208680D01*
G01X745485Y197673D02*
X748645Y200833D01*
G01X712587Y225714D02*
X725009Y213292D01*
G01X712587Y237247D02*
Y225714D01*
G01X710708Y239126D02*
X712587Y237247D01*
G01X758645Y204535D02*
X764569Y210459D01*
G01X758645Y194727D02*
Y204535D01*
G01X747383Y183465D02*
X758645Y194727D01*
G01X743252Y183465D02*
X747383D01*
G01X742502Y182715D02*
X743252Y183465D01*
G01X741814Y197877D02*
X739852Y195915D01*
G01X741814Y203816D02*
Y197877D01*
G01X743645Y205647D02*
X741814Y203816D01*
G01X743645Y211993D02*
Y205647D01*
G01X744839Y213187D02*
X743645Y211993D01*
G01X744839Y223687D02*
Y213187D01*
G01X753558Y232406D02*
X744839Y223687D01*
G01X753558Y246477D02*
Y232406D01*
G01X751558Y233431D02*
Y246477D01*
G01X751058Y232931D02*
X751558Y233431D01*
G01X750058Y232931D02*
X751058D01*
G01X749558Y233431D02*
X750058Y232931D01*
G01X749558Y249040D02*
Y233431D01*
G01X738230Y185827D02*
X729920D01*
G01X738268Y185865D02*
X738230Y185827D01*
G01X742668Y185865D02*
X738268D01*
G01X743068Y185465D02*
X742668Y185865D01*
G01X746554Y185465D02*
X743068D01*
G01X756645Y195556D02*
X746554Y185465D01*
G01X756645Y205364D02*
Y195556D01*
G01X758839Y207558D02*
X756645Y205364D01*
G01X758839Y211362D02*
Y207558D01*
G01X759527Y212050D02*
X758839Y211362D01*
G01X746645Y202833D02*
X745485Y201673D01*
G01X746645Y209509D02*
Y202833D01*
G01X748839Y211703D02*
X746645Y209509D01*
G01X748839Y222029D02*
Y211703D01*
G01X757558Y230748D02*
X748839Y222029D01*
G01X757558Y245274D02*
Y230748D01*
G01X741402Y179065D02*
X740352Y180115D01*
G01X748641Y179065D02*
X741402D01*
G01X764839Y195263D02*
X748641Y179065D01*
G01X706708Y223416D02*
Y270479D01*
G01X707890Y222234D02*
X706708Y223416D01*
G01X707890Y221526D02*
Y222234D01*
G01X706876Y220512D02*
X707890Y221526D01*
G01X706876Y219804D02*
Y220512D01*
G01X707583Y219097D02*
X706876Y219804D01*
G01X708291Y219097D02*
X707583D01*
G01X709305Y220111D02*
X708291Y219097D01*
G01X710013Y220111D02*
X709305D01*
G01X710720Y219404D02*
X710013Y220111D01*
G01X710720Y218696D02*
Y219404D01*
G01X709091Y217067D02*
X710720Y218696D01*
G01X709091Y216359D02*
Y217067D01*
G01X709798Y215652D02*
X709091Y216359D01*
G01X710506Y215652D02*
X709798D01*
G01X712135Y217281D02*
X710506Y215652D01*
G01X712843Y217281D02*
X712135D01*
G01X713550Y216574D02*
X712843Y217281D01*
G01X713550Y215866D02*
Y216574D01*
G01X711921Y214237D02*
X713550Y215866D01*
G01X711921Y213529D02*
Y214237D01*
G01X712628Y212822D02*
X711921Y213529D01*
G01X713336Y212822D02*
X712628D01*
G01X714965Y214451D02*
X713336Y212822D01*
G01X715673Y214451D02*
X714965D01*
G01X720324Y209800D02*
X715673Y214451D01*
G01X720819Y209800D02*
X720324D01*
G01X739752Y203169D02*
Y199615D01*
G01X741839Y205256D02*
X739752Y203169D01*
G01X741839Y212671D02*
Y205256D01*
G01X742839Y213671D02*
X741839Y212671D01*
G01X742839Y225643D02*
Y213671D01*
G01X741033Y227449D02*
X742839Y225643D01*
G01X741033Y232725D02*
Y227449D01*
G01X743388Y235080D02*
X741033Y232725D01*
G01X743388Y236776D02*
Y235080D01*
G01X743888Y237276D02*
X743388Y236776D01*
G01X744888Y237276D02*
X743888D01*
G01X745388Y236776D02*
X744888Y237276D01*
G01X745388Y229137D02*
Y236776D01*
G01X745888Y228637D02*
X745388Y229137D01*
G01X746888Y228637D02*
X745888D01*
G01X747388Y229137D02*
X746888Y228637D01*
G01X747388Y243726D02*
Y229137D01*
G01X736587Y208496D02*
X736272Y208181D01*
G01X736587Y220302D02*
Y208496D01*
G01X736087Y220802D02*
X736587Y220302D01*
G01X735087Y220802D02*
X736087D01*
G01X734587Y220302D02*
X735087Y220802D01*
G01X734587Y217238D02*
Y220302D01*
G01X734087Y216738D02*
X734587Y217238D01*
G01X733087Y216738D02*
X734087D01*
G01X732587Y217238D02*
X733087Y216738D01*
G01X732587Y228368D02*
Y217238D01*
G01X732087Y228868D02*
X732587Y228368D01*
G01X729087Y228868D02*
X732087D01*
G01X728587Y229368D02*
X729087Y228868D01*
G01X728587Y230368D02*
Y229368D01*
G01X729087Y230868D02*
X728587Y230368D01*
G01X732051Y230868D02*
X729087D01*
G01X732551Y231368D02*
X732051Y230868D01*
G01X732551Y232368D02*
Y231368D01*
G01X732051Y232868D02*
X732551Y232368D01*
G01X729087Y232868D02*
X732051D01*
G01X728587Y233368D02*
X729087Y232868D01*
G01X728587Y236599D02*
Y233368D01*
G01X729087Y237099D02*
X728587Y236599D01*
G01X732087Y237099D02*
X729087D01*
G01X732587Y237599D02*
X732087Y237099D01*
G01X738839Y220911D02*
Y206080D01*
G01X734603Y225147D02*
X738839Y220911D01*
G01X734603Y235480D02*
Y225147D01*
G01X735871Y236748D02*
X734603Y235480D01*
G01X735871Y250633D02*
Y236748D01*
G01X739084Y237360D02*
X738584Y237860D01*
G01X740615Y237360D02*
X739084D01*
G01X741115Y236860D02*
X740615Y237360D01*
G01X741115Y235860D02*
Y236860D01*
G01X740615Y235360D02*
X741115Y235860D01*
G01X737312Y235360D02*
X740615D01*
G01X736812Y234860D02*
X737312Y235360D01*
G01X736812Y233860D02*
Y234860D01*
G01X737312Y233360D02*
X736812Y233860D01*
G01X738406Y233360D02*
X737312D01*
G01X738906Y232860D02*
X738406Y233360D01*
G01X738906Y231860D02*
Y232860D01*
G01X738406Y231360D02*
X738906Y231860D01*
G01X737312Y231360D02*
X738406D01*
G01X736812Y230860D02*
X737312Y231360D01*
G01X736812Y229860D02*
Y230860D01*
G01X737312Y229360D02*
X736812Y229860D01*
G01X738511Y229360D02*
X737312D01*
G01X739011Y228860D02*
X738511Y229360D01*
G01X739011Y227860D02*
Y228860D01*
G01X738511Y227360D02*
X739011Y227860D01*
G01X737312Y227360D02*
X738511D01*
G01X736812Y226860D02*
X737312Y227360D01*
G01X736812Y225785D02*
Y226860D01*
G01X737312Y225285D02*
X736812Y225785D01*
G01X740339Y225285D02*
X737312D01*
G01X740839Y224785D02*
X740339Y225285D01*
G01X740839Y205671D02*
Y224785D01*
G01X737832Y202664D02*
X740839Y205671D01*
G01X730896Y208414D02*
X729136Y206654D01*
G01X730896Y213271D02*
Y208414D01*
G01X726315Y217852D02*
X730896Y213271D01*
G01X726315Y218739D02*
Y217852D01*
G01X726815Y219239D02*
X726315Y218739D01*
G01X727986Y219239D02*
X726815D01*
G01X728486Y219739D02*
X727986Y219239D01*
G01X728486Y220739D02*
Y219739D01*
G01X727986Y221239D02*
X728486Y220739D01*
G01X726815Y221239D02*
X727986D01*
G01X726315Y221739D02*
X726815Y221239D01*
G01X726315Y225508D02*
Y221739D01*
G01X724587Y227236D02*
X726315Y225508D01*
G01X724587Y231472D02*
Y227236D01*
G01X724087Y231972D02*
X724587Y231472D01*
G01X723087Y231972D02*
X724087D01*
G01X722587Y231472D02*
X723087Y231972D01*
G01X722587Y224064D02*
Y231472D01*
G01X722087Y223564D02*
X722587Y224064D01*
G01X721087Y223564D02*
X722087D01*
G01X720587Y224064D02*
X721087Y223564D01*
G01X720587Y262571D02*
Y224064D01*
G01X747812Y181065D02*
X762839Y196092D01*
G01X741818Y181065D02*
X747812D01*
G01X740890Y181993D02*
X741818Y181065D01*
G01X730605Y181993D02*
X740890D01*
G01X729920Y182678D02*
X730605Y181993D01*
G01X743153Y190551D02*
X738416D01*
G01X750645Y198043D02*
X743153Y190551D01*
G01X750645Y207851D02*
Y198043D01*
G01X752839Y210045D02*
X750645Y207851D01*
G01X752839Y220318D02*
Y210045D01*
G01X761934Y229413D02*
X752839Y220318D01*
G01X755111Y219761D02*
X763348Y227998D01*
G01X755111Y219055D02*
Y219761D01*
G01X755819Y218346D02*
X755111Y219055D01*
G01X756525Y218346D02*
X755819D01*
G01X766436Y228257D02*
X756525Y218346D01*
G01X737656Y188977D02*
X729920D01*
G01X737732Y188901D02*
X737656Y188977D01*
G01X744332Y188901D02*
X737732D01*
G01X752645Y197214D02*
X744332Y188901D01*
G01X752645Y207022D02*
Y197214D01*
G01X754839Y209216D02*
X752645Y207022D01*
G01X754839Y213831D02*
Y209216D01*
G01X768436Y227428D02*
X754839Y213831D01*
G01X749420Y177015D02*
X742252D01*
G01X766839Y194434D02*
X749420Y177015D01*
G01X755558Y231577D02*
Y246103D01*
G01X746839Y222858D02*
X755558Y231577D01*
G01X746839Y212758D02*
Y222858D01*
G01X744741Y210660D02*
X746839Y212758D01*
G01X744741Y204380D02*
Y210660D01*
G01X743198Y202837D02*
X744741Y204380D01*
G01X743198Y196356D02*
Y202837D01*
G01X739273Y192431D02*
X743198Y196356D01*
G01X730225Y192431D02*
X739273D01*
G01X729920Y192126D02*
X730225Y192431D01*
G01X702583Y213716D02*
Y254522D01*
G01X708658Y207641D02*
X702583Y213716D01*
G01X708658Y205092D02*
Y207641D01*
G01X705140Y201574D02*
X708658Y205092D01*
G01X704724Y201574D02*
X705140D01*
G01X729246Y211893D02*
Y209941D01*
G01X718587Y222552D02*
X729246Y211893D01*
G01X718587Y231986D02*
Y222552D01*
G01X718087Y232486D02*
X718587Y231986D01*
G01X717087Y232486D02*
X718087D01*
G01X716587Y231986D02*
X717087Y232486D01*
G01X716587Y226775D02*
Y231986D01*
G01X716087Y226275D02*
X716587Y226775D01*
G01X715087Y226275D02*
X716087D01*
G01X714587Y226775D02*
X715087Y226275D01*
G01X714587Y262454D02*
Y226775D01*
G01X717087Y237029D02*
X716587Y237529D01*
G01X718087Y237029D02*
X717087D01*
G01X718587Y237529D02*
X718087Y237029D01*
G01X708708Y236953D02*
Y244294D01*
G01X709208Y236453D02*
X708708Y236953D01*
G01X710044Y236453D02*
X709208D01*
G01X710544Y235953D02*
X710044Y236453D01*
G01X710544Y234953D02*
Y235953D01*
G01X710044Y234453D02*
X710544Y234953D01*
G01X709208Y234453D02*
X710044D01*
G01X708708Y233953D02*
X709208Y234453D01*
G01X708708Y232953D02*
Y233953D01*
G01X709208Y232453D02*
X708708Y232953D01*
G01X710044Y232453D02*
X709208D01*
G01X710544Y231953D02*
X710044Y232453D01*
G01X710544Y230953D02*
Y231953D01*
G01X710044Y230453D02*
X710544Y230953D01*
G01X709208Y230453D02*
X710044D01*
G01X708708Y229953D02*
X709208Y230453D01*
G01X708708Y228953D02*
Y229953D01*
G01X709208Y228453D02*
X708708Y228953D01*
G01X710044Y228453D02*
X709208D01*
G01X710544Y227953D02*
X710044Y228453D01*
G01X710544Y226953D02*
Y227953D01*
G01X710044Y226453D02*
X710544Y226953D01*
G01X709208Y226453D02*
X710044D01*
G01X708708Y225953D02*
X709208Y226453D01*
G01X708708Y224245D02*
Y225953D01*
G01X709933Y223020D02*
X708708Y224245D01*
G01X710641Y223020D02*
X709933D01*
G01X711141Y223520D02*
X710641Y223020D01*
G01X711849Y223520D02*
X711141D01*
G01X712556Y222813D02*
X711849Y223520D01*
G01X712556Y222105D02*
Y222813D01*
G01X712056Y221605D02*
X712556Y222105D01*
G01X712056Y220897D02*
Y221605D01*
G01X714521Y218432D02*
X712056Y220897D01*
G01X715227Y218432D02*
X714521D01*
G01X715702Y218906D02*
X715227Y218432D01*
G01X716408Y218906D02*
X715702D01*
G01X717117Y218197D02*
X716408Y218906D01*
G01X717117Y217491D02*
Y218197D01*
G01X716642Y217017D02*
X717117Y217491D01*
G01X716642Y216311D02*
Y217017D01*
G01X717351Y215602D02*
X716642Y216311D01*
G01X718057Y215602D02*
X717351D01*
G01X718532Y216076D02*
X718057Y215602D01*
G01X719238Y216076D02*
X718532D01*
G01X719947Y215367D02*
X719238Y216076D01*
G01X719947Y214661D02*
Y215367D01*
G01X719472Y214187D02*
X719947Y214661D01*
G01X719472Y213481D02*
Y214187D01*
G01X720181Y212772D02*
X719472Y213481D01*
G01X720887Y212772D02*
X720181D01*
G01X721362Y213246D02*
X720887Y212772D01*
G01X722068Y213246D02*
X721362D01*
G01X722777Y212537D02*
X722068Y213246D01*
G01X722777Y211831D02*
Y212537D01*
G01X722302Y211357D02*
X722777Y211831D01*
G01X722302Y210651D02*
Y211357D01*
G01X722990Y209963D02*
X722302Y210651D01*
G01X724776Y209963D02*
X722990D01*
G01X724806Y236152D02*
X726587Y237933D01*
G01X724806Y234477D02*
Y236152D01*
G01X726587Y232696D02*
X724806Y234477D01*
G01X726587Y228539D02*
Y232696D01*
G01X728844Y226282D02*
X726587Y228539D01*
G01X728844Y223706D02*
Y226282D01*
G01X730587Y221963D02*
X728844Y223706D01*
G01X730587Y216409D02*
Y221963D01*
G01X733565Y213431D02*
X730587Y216409D01*
G01X733565Y210184D02*
Y213431D01*
G01X710708Y242225D02*
Y239126D01*
G01X712587Y244104D02*
X710708Y242225D01*
G01X712587Y263283D02*
Y244104D01*
G01X720421Y271117D02*
X712587Y263283D01*
G01X720421Y278534D02*
Y271117D01*
G01X727458Y285571D02*
X720421Y278534D01*
G01X737260Y285571D02*
X727458D01*
G01X739300Y287611D02*
X737260Y285571D01*
G01X753058Y246977D02*
X753558Y246477D01*
G01X752058Y246977D02*
X753058D01*
G01X751558Y246477D02*
X752058Y246977D01*
G01X750058Y249540D02*
X749558Y249040D01*
G01X756059Y249540D02*
X750058D01*
G01X756559Y250040D02*
X756059Y249540D01*
G01X756559Y251040D02*
Y250040D01*
G01X756059Y251540D02*
X756559Y251040D01*
G01X750337Y251540D02*
X756059D01*
G01X749837Y252040D02*
X750337Y251540D01*
G01X749837Y253040D02*
Y252040D01*
G01X750337Y253540D02*
X749837Y253040D01*
G01X756912Y253540D02*
X750337D01*
G01X757412Y254040D02*
X756912Y253540D01*
G01X757412Y255040D02*
Y254040D01*
G01X756912Y255540D02*
X757412Y255040D01*
G01X751693Y255540D02*
X756912D01*
G01X759558Y247274D02*
X757558Y245274D01*
G01X735300Y289135D02*
Y287611D01*
G01X735800Y289635D02*
X735300Y289135D01*
G01X738781Y289635D02*
X735800D01*
G01X739281Y290135D02*
X738781Y289635D01*
G01X739281Y300386D02*
Y290135D01*
G01X736906Y297386D02*
Y300386D01*
G01X736406Y296886D02*
X736906Y297386D01*
G01X733300Y296886D02*
X736406D01*
G01X732800Y296386D02*
X733300Y296886D01*
G01X732800Y295386D02*
Y296386D01*
G01X733300Y294886D02*
X732800Y295386D01*
G01X736468Y294886D02*
X733300D01*
G01X736968Y294386D02*
X736468Y294886D01*
G01X736968Y293386D02*
Y294386D01*
G01X736468Y292886D02*
X736968Y293386D01*
G01X729115Y292886D02*
X736468D01*
G01X706708Y270479D02*
X729115Y292886D01*
G01X745558Y245556D02*
X747388Y243726D01*
G01X745558Y280189D02*
Y245556D01*
G01X746058Y280689D02*
X745558Y280189D01*
G01X747058Y280689D02*
X746058D01*
G01X747558Y280189D02*
X747058Y280689D01*
G01X747558Y247274D02*
Y280189D01*
G01X732587Y272816D02*
Y237599D01*
G01X733087Y273316D02*
X732587Y272816D01*
G01X734087Y273316D02*
X733087D01*
G01X734587Y272816D02*
X734087Y273316D01*
G01X734587Y254479D02*
Y272816D01*
G01X735087Y253979D02*
X734587Y254479D01*
G01X736087Y253979D02*
X735087D01*
G01X736587Y254479D02*
X736087Y253979D01*
G01X736587Y282302D02*
Y254479D01*
G01X735378Y283511D02*
X736587Y282302D01*
G01X735318Y283511D02*
X735378D01*
G01X735318Y283571D02*
Y283511D01*
G01X739318Y254080D02*
X735871Y250633D01*
G01X739318Y279924D02*
Y254080D01*
G01X739818Y280424D02*
X739318Y279924D01*
G01X740818Y280424D02*
X739818D01*
G01X741318Y279924D02*
X740818Y280424D01*
G01X741318Y278611D02*
Y279924D01*
G01X741818Y278111D02*
X741318Y278611D01*
G01X742818Y278111D02*
X741818D01*
G01X743318Y278611D02*
X742818Y278111D01*
G01X743318Y282304D02*
Y278611D01*
G01X743818Y282804D02*
X743318Y282304D01*
G01X746230Y282804D02*
X743818D01*
G01X746730Y283304D02*
X746230Y282804D01*
G01X746730Y284304D02*
Y283304D01*
G01X746230Y284804D02*
X746730Y284304D01*
G01X744276Y284804D02*
X746230D01*
G01X743776Y285304D02*
X744276Y284804D01*
G01X743776Y286304D02*
Y285304D01*
G01X744276Y286804D02*
X743776Y286304D01*
G01X746230Y286804D02*
X744276D01*
G01X746730Y287304D02*
X746230Y286804D01*
G01X746730Y288304D02*
Y287304D01*
G01X746230Y288804D02*
X746730Y288304D01*
G01X744276Y288804D02*
X746230D01*
G01X743776Y289304D02*
X744276Y288804D01*
G01X743776Y290304D02*
Y289304D01*
G01X744276Y290804D02*
X743776Y290304D01*
G01X746230Y290804D02*
X744276D01*
G01X746730Y291304D02*
X746230Y290804D01*
G01X746730Y292304D02*
Y291304D01*
G01X746230Y292804D02*
X746730Y292304D01*
G01X744276Y292804D02*
X746230D01*
G01X743776Y293304D02*
X744276Y292804D01*
G01X743776Y294304D02*
Y293304D01*
G01X744276Y294804D02*
X743776Y294304D01*
G01X746230Y294804D02*
X744276D01*
G01X746730Y295304D02*
X746230Y294804D01*
G01X746730Y296304D02*
Y295304D01*
G01X746230Y296804D02*
X746730Y296304D01*
G01X744276Y296804D02*
X746230D01*
G01X743776Y297304D02*
X744276Y296804D01*
G01X743776Y298304D02*
Y297304D01*
G01X744276Y298804D02*
X743776Y298304D01*
G01X746230Y298804D02*
X744276D01*
G01X746730Y299304D02*
X746230Y298804D01*
G01X746730Y300304D02*
Y299304D01*
G01X741318Y284071D02*
Y300304D01*
G01X740818Y283571D02*
X741318Y284071D01*
G01X739318Y283571D02*
X740818D01*
G01X743507Y272416D02*
Y251685D01*
G01X743007Y272916D02*
X743507Y272416D01*
G01X741888Y272916D02*
X743007D01*
G01X741388Y272416D02*
X741888Y272916D01*
G01X741388Y251860D02*
Y272416D01*
G01X740888Y251360D02*
X741388Y251860D01*
G01X739427Y251360D02*
X740888D01*
G01X738927Y250860D02*
X739427Y251360D01*
G01X738927Y249860D02*
Y250860D01*
G01X739427Y249360D02*
X738927Y249860D01*
G01X742868Y249360D02*
X739427D01*
G01X743368Y248860D02*
X742868Y249360D01*
G01X743368Y247860D02*
Y248860D01*
G01X742868Y247360D02*
X743368Y247860D01*
G01X739135Y247360D02*
X742868D01*
G01X738635Y246860D02*
X739135Y247360D01*
G01X738635Y245860D02*
Y246860D01*
G01X739135Y245360D02*
X738635Y245860D01*
G01X742555Y245360D02*
X739135D01*
G01X743055Y244860D02*
X742555Y245360D01*
G01X743055Y243860D02*
Y244860D01*
G01X742555Y243360D02*
X743055Y243860D01*
G01X739031Y243360D02*
X742555D01*
G01X738531Y242860D02*
X739031Y243360D01*
G01X738531Y241860D02*
Y242860D01*
G01X739031Y241360D02*
X738531Y241860D01*
G01X744804Y241360D02*
X739031D01*
G01X745304Y240860D02*
X744804Y241360D01*
G01X745304Y239860D02*
Y240860D01*
G01X744804Y239360D02*
X745304Y239860D01*
G01X739084Y239360D02*
X744804D01*
G01X738584Y238860D02*
X739084Y239360D01*
G01X738584Y237860D02*
Y238860D01*
G01X721087Y263071D02*
X720587Y262571D01*
G01X722087Y263071D02*
X721087D01*
G01X722587Y262571D02*
X722087Y263071D01*
G01X722587Y239321D02*
Y262571D01*
G01X723087Y238821D02*
X722587Y239321D01*
G01X724087Y238821D02*
X723087D01*
G01X724587Y239321D02*
X724087Y238821D01*
G01X724587Y277042D02*
Y239321D01*
G01X727181Y279636D02*
X724587Y277042D01*
G01X731155Y279636D02*
X727181D01*
G01X751693Y262149D02*
Y259540D01*
G01X752193Y262649D02*
X751693Y262149D01*
G01X756890Y262649D02*
X752193D01*
G01X757390Y263149D02*
X756890Y262649D01*
G01X757390Y264149D02*
Y263149D01*
G01X756890Y264649D02*
X757390Y264149D01*
G01X750193Y264649D02*
X756890D01*
G01X749693Y265149D02*
X750193Y264649D01*
G01X749693Y266149D02*
Y265149D01*
G01X750193Y266649D02*
X749693Y266149D01*
G01X756974Y266649D02*
X750193D01*
G01X757474Y267149D02*
X756974Y266649D01*
G01X757474Y268149D02*
Y267149D01*
G01X756974Y268649D02*
X757474Y268149D01*
G01X750193Y268649D02*
X756974D01*
G01X749693Y269149D02*
X750193Y268649D01*
G01X749693Y270149D02*
Y269149D01*
G01X750193Y270649D02*
X749693Y270149D01*
G01X759058Y270649D02*
X750193D01*
G01X759558Y270149D02*
X759058Y270649D01*
G01X755558Y246103D02*
X759558Y250103D01*
G01X702583Y254522D02*
X704708Y256647D01*
G01X715087Y262954D02*
X714587Y262454D01*
G01X716087Y262954D02*
X715087D01*
G01X716587Y262454D02*
X716087Y262954D01*
G01X716587Y237529D02*
Y262454D01*
G01X718587Y265941D02*
Y237529D01*
G01X722421Y269775D02*
X718587Y265941D01*
G01X722421Y277705D02*
Y269775D01*
G01X728287Y283571D02*
X722421Y277705D01*
G01X731318Y283571D02*
X728287D01*
G01X726669Y287611D02*
X731300D01*
G01X708745Y269687D02*
X726669Y287611D01*
G01X708745Y268979D02*
Y269687D01*
G01X709452Y268272D02*
X708745Y268979D01*
G01X710160Y268272D02*
X709452D01*
G01X716784Y274896D02*
X710160Y268272D01*
G01X717492Y274896D02*
X716784D01*
G01X718199Y274189D02*
X717492Y274896D01*
G01X718199Y273481D02*
Y274189D01*
G01X708708Y263990D02*
X718199Y273481D01*
G01X708708Y263294D02*
Y263990D01*
G01X709208Y262794D02*
X708708Y263294D01*
G01X709856Y262794D02*
X709208D01*
G01X710356Y262294D02*
X709856Y262794D01*
G01X710356Y261294D02*
Y262294D01*
G01X709856Y260794D02*
X710356Y261294D01*
G01X709208Y260794D02*
X709856D01*
G01X708708Y260294D02*
X709208Y260794D01*
G01X708708Y259294D02*
Y260294D01*
G01X709208Y258794D02*
X708708Y259294D01*
G01X710085Y258794D02*
X709208D01*
G01X710585Y258294D02*
X710085Y258794D01*
G01X710585Y257294D02*
Y258294D01*
G01X710085Y256794D02*
X710585Y257294D01*
G01X709208Y256794D02*
X710085D01*
G01X708708Y256294D02*
X709208Y256794D01*
G01X708708Y255294D02*
Y256294D01*
G01X709208Y254794D02*
X708708Y255294D01*
G01X710085Y254794D02*
X709208D01*
G01X710585Y254294D02*
X710085Y254794D01*
G01X710585Y253294D02*
Y254294D01*
G01X710085Y252794D02*
X710585Y253294D01*
G01X709208Y252794D02*
X710085D01*
G01X708708Y252294D02*
X709208Y252794D01*
G01X708708Y251294D02*
Y252294D01*
G01X709208Y250794D02*
X708708Y251294D01*
G01X710085Y250794D02*
X709208D01*
G01X710585Y250294D02*
X710085Y250794D01*
G01X710585Y249294D02*
Y250294D01*
G01X710085Y248794D02*
X710585Y249294D01*
G01X709208Y248794D02*
X710085D01*
G01X708708Y248294D02*
X709208Y248794D01*
G01X708708Y247294D02*
Y248294D01*
G01X709208Y246794D02*
X708708Y247294D01*
G01X710085Y246794D02*
X709208D01*
G01X710585Y246294D02*
X710085Y246794D01*
G01X710585Y245294D02*
Y246294D01*
G01X710085Y244794D02*
X710585Y245294D01*
G01X709208Y244794D02*
X710085D01*
G01X708708Y244294D02*
X709208Y244794D01*
G01X702764Y266591D02*
X704708Y264647D01*
G01X702764Y274686D02*
Y266591D01*
G01X755300Y327222D02*
X702764Y274686D01*
G01X731087Y275696D02*
X734638D01*
G01X730587Y275196D02*
X731087Y275696D01*
G01X730587Y240142D02*
Y275196D01*
G01X730087Y239642D02*
X730587Y240142D01*
G01X729087Y239642D02*
X730087D01*
G01X728587Y240142D02*
X729087Y239642D01*
G01X728587Y275165D02*
Y240142D01*
G01X728087Y275665D02*
X728587Y275165D01*
G01X727087Y275665D02*
X728087D01*
G01X726587Y275165D02*
X727087Y275665D01*
G01X726587Y237933D02*
Y275165D01*
G01X738781Y300886D02*
X739281Y300386D01*
G01X737406Y300886D02*
X738781D01*
G01X736906Y300386D02*
X737406Y300886D01*
G01X746230Y300804D02*
X746730Y300304D01*
G01X741818Y300804D02*
X746230D01*
G01X741318Y300304D02*
X741818Y300804D01*
G01X755300Y408742D02*
Y327222D01*
G01X746127Y417915D02*
X755300Y408742D01*
G01X775435Y87521D02*
X801350Y113436D01*
G01X772804Y87521D02*
X775435D01*
G01X767359Y82076D02*
X772804Y87521D01*
G01X798762Y141207D02*
Y210038D01*
G01X801350Y138619D02*
X798762Y141207D01*
G01X801350Y113436D02*
Y138619D01*
G01X772511Y224355D02*
X768219D01*
G01X774146Y225990D02*
X772511Y224355D01*
G01X774146Y226638D02*
Y225990D01*
G01X773646Y227138D02*
X774146Y226638D01*
G01X770936Y227138D02*
X773646D01*
G01X770436Y227638D02*
X770936Y227138D01*
G01X770436Y228638D02*
Y227638D01*
G01X770936Y229138D02*
X770436Y228638D01*
G01X773313Y229138D02*
X770936D01*
G01X773813Y229638D02*
X773313Y229138D01*
G01X773813Y230638D02*
Y229638D01*
G01X773313Y231138D02*
X773813Y230638D01*
G01X770936Y231138D02*
X773313D01*
G01X770436Y231638D02*
X770936Y231138D01*
G01X770436Y232638D02*
Y231638D01*
G01X770936Y233138D02*
X770436Y232638D01*
G01X773313Y233138D02*
X770936D01*
G01X773813Y233638D02*
X773313Y233138D01*
G01X773813Y234638D02*
Y233638D01*
G01X773313Y235138D02*
X773813Y234638D01*
G01X770936Y235138D02*
X773313D01*
G01X770436Y235638D02*
X770936Y235138D01*
G01X770436Y236638D02*
Y235638D01*
G01X770936Y237138D02*
X770436Y236638D01*
G01X773303Y237138D02*
X770936D01*
G01X773803Y237638D02*
X773303Y237138D01*
G01X759558Y229919D02*
Y241027D01*
G01X778725Y224874D02*
Y242741D01*
G01X773316Y219465D02*
X778725Y224874D01*
G01X769484Y219465D02*
X773316D01*
G01X764569Y214550D02*
X769484Y219465D01*
G01X764569Y210459D02*
Y214550D01*
G01X761936Y212050D02*
X759527D01*
G01X762566Y212680D02*
X761936Y212050D01*
G01X762566Y215376D02*
Y212680D01*
G01X768966Y221776D02*
X762566Y215376D01*
G01X772798Y221776D02*
X768966D01*
G01X776420Y225398D02*
X772798Y221776D01*
G01X776420Y247074D02*
Y225398D01*
G01X801618Y214116D02*
Y300280D01*
G01X799564Y212170D02*
X801618Y210116D01*
G01X799564Y301269D02*
Y212170D01*
G01X764839Y205071D02*
Y195263D01*
G01X768833Y209065D02*
X764839Y205071D01*
G01X768833Y213156D02*
Y209065D01*
G01X770204Y214527D02*
X768833Y213156D01*
G01X774140Y214527D02*
X770204D01*
G01X782837Y223224D02*
X774140Y214527D01*
G01X782837Y254375D02*
Y223224D01*
G01X797564Y211236D02*
Y287714D01*
G01X798762Y210038D02*
X797564Y211236D01*
G01X780837Y224157D02*
Y240885D01*
G01X773803Y217123D02*
X780837Y224157D01*
G01X769971Y217123D02*
X773803D01*
G01X766569Y213721D02*
X769971Y217123D01*
G01X766569Y209630D02*
Y213721D01*
G01X762839Y205900D02*
X766569Y209630D01*
G01X762839Y196092D02*
Y205900D01*
G01X762640Y229413D02*
X761934D01*
G01X763348Y228704D02*
X762640Y229413D01*
G01X763348Y227998D02*
Y228704D01*
G01X766436Y234903D02*
Y228257D01*
G01X765936Y235403D02*
X766436Y234903D01*
G01X764936Y235403D02*
X765936D01*
G01X764436Y234903D02*
X764936Y235403D01*
G01X764436Y232235D02*
Y234903D01*
G01X763936Y231735D02*
X764436Y232235D01*
G01X762936Y231735D02*
X763936D01*
G01X762436Y232235D02*
X762936Y231735D01*
G01X762436Y250629D02*
Y232235D01*
G01X768436Y249061D02*
Y227428D01*
G01X766839Y204097D02*
Y194434D01*
G01X784837Y222095D02*
X766839Y204097D01*
G01X784837Y255204D02*
Y222095D01*
G01X768898Y203327D02*
Y193664D01*
G01X786941Y221370D02*
X768898Y203327D01*
G01X786941Y233535D02*
Y221370D01*
G01X790714Y237308D02*
X786941Y233535D01*
G01X773803Y238638D02*
Y237638D01*
G01X773303Y239138D02*
X773803Y238638D01*
G01X770936Y239138D02*
X773303D01*
G01X770436Y239638D02*
X770936Y239138D01*
G01X770436Y240638D02*
Y239638D01*
G01X770936Y241138D02*
X770436Y240638D01*
G01X773157Y241138D02*
X770936D01*
G01X773657Y241638D02*
X773157Y241138D01*
G01X773657Y242638D02*
Y241638D01*
G01X773157Y243138D02*
X773657Y242638D01*
G01X770936Y243138D02*
X773157D01*
G01X770436Y243638D02*
X770936Y243138D01*
G01X770436Y244638D02*
Y243638D01*
G01X770936Y245138D02*
X770436Y244638D01*
G01X773646Y245138D02*
X770936D01*
G01X774146Y245638D02*
X773646Y245138D01*
G01X774146Y246519D02*
Y245638D01*
G01X768637Y252028D02*
X774146Y246519D01*
G01X768637Y255594D02*
Y252028D01*
G01X764596Y259635D02*
X768637Y255594D01*
G01X761638Y259635D02*
X764596D01*
G01X778725Y255658D02*
X774637Y259746D01*
G01X778725Y253741D02*
Y255658D01*
G01X779225Y253241D02*
X778725Y253741D01*
G01X780091Y253241D02*
X779225D01*
G01X780591Y252741D02*
X780091Y253241D01*
G01X780591Y251741D02*
Y252741D01*
G01X780091Y251241D02*
X780591Y251741D01*
G01X779225Y251241D02*
X780091D01*
G01X778725Y250741D02*
X779225Y251241D01*
G01X778725Y249741D02*
Y250741D01*
G01X779225Y249241D02*
X778725Y249741D01*
G01X780091Y249241D02*
X779225D01*
G01X780591Y248741D02*
X780091Y249241D01*
G01X780591Y247741D02*
Y248741D01*
G01X780091Y247241D02*
X780591Y247741D01*
G01X779225Y247241D02*
X780091D01*
G01X778725Y246741D02*
X779225Y247241D01*
G01X778725Y245741D02*
Y246741D01*
G01X779225Y245241D02*
X778725Y245741D01*
G01X780091Y245241D02*
X779225D01*
G01X780591Y244741D02*
X780091Y245241D01*
G01X780591Y243741D02*
Y244741D01*
G01X780091Y243241D02*
X780591Y243741D01*
G01X779225Y243241D02*
X780091D01*
G01X778725Y242741D02*
X779225Y243241D01*
G01X770637Y252857D02*
X776420Y247074D01*
G01X770637Y257028D02*
Y252857D01*
G01X768730Y258935D02*
X770637Y257028D01*
G01X768730Y265839D02*
Y258935D01*
G01X770637Y267746D02*
X768730Y265839D01*
G01X775466Y261746D02*
X782837Y254375D01*
G01X773808Y261746D02*
X775466D01*
G01X772637Y262917D02*
X773808Y261746D01*
G01X772637Y265746D02*
Y262917D01*
G01X774637Y267746D02*
X772637Y265746D01*
G01X765508Y289846D02*
X763292Y287630D01*
G01X795432Y289846D02*
X765508D01*
G01X797564Y287714D02*
X795432Y289846D01*
G01X761484Y251581D02*
X762436Y250629D01*
G01X767936Y249561D02*
X768436Y249061D01*
G01X766936Y249561D02*
X767936D01*
G01X766436Y249061D02*
X766936Y249561D01*
G01X766436Y238224D02*
Y249061D01*
G01X765936Y237724D02*
X766436Y238224D01*
G01X764936Y237724D02*
X765936D01*
G01X764436Y238224D02*
X764936Y237724D01*
G01X764436Y252629D02*
Y238224D01*
G01X761484Y255581D02*
X764436Y252629D01*
G01X776295Y263746D02*
X784837Y255204D01*
G01X774637Y263746D02*
X776295D01*
G01X759558Y250103D02*
Y270149D01*
G01X801618Y300280D02*
X801853Y300515D01*
G01X801728Y303433D02*
X799564Y301269D01*
G01X801728Y304572D02*
Y303433D01*
G54D12*
G01X6250Y-135162D02*
Y-152662D01*
G01X1228Y-135162D02*
X11272D01*
G01X20038Y-152662D02*
Y-135162D01*
G01Y-143620D02*
X21130Y-142162D01*
X22222Y-141287D01*
X23968Y-140996D01*
X25278Y-141287D01*
X26807Y-142454D01*
X27462Y-144204D01*
Y-152662D01*
G01X41250Y-140996D02*
Y-152662D01*
G01Y-136329D02*
X40813Y-136037D01*
Y-135454D01*
X41250Y-135162D01*
X41687Y-135454D01*
Y-136037D01*
X41250Y-136329D01*
G01X55475Y-150621D02*
X56567Y-151787D01*
X58095Y-152662D01*
X59405D01*
X60715Y-152079D01*
X61588Y-151204D01*
X62025Y-150038D01*
X61807Y-148287D01*
X60933Y-147412D01*
X57003Y-145662D01*
X56130Y-143620D01*
X56567Y-142162D01*
X57440Y-141287D01*
X58750Y-140996D01*
X60060Y-141287D01*
X61370Y-142162D01*
G01X90693Y-157037D02*
X92222Y-158204D01*
X93968Y-158495D01*
X95496Y-158204D01*
X96807Y-156746D01*
X97680Y-154704D01*
Y-140996D01*
G01Y-143329D02*
X96807Y-142162D01*
X95496Y-141287D01*
X93968Y-140996D01*
X92222Y-141579D01*
X91130Y-142745D01*
X90256Y-144787D01*
X89820Y-146829D01*
X90038Y-148579D01*
X90912Y-150621D01*
X92222Y-152079D01*
X93968Y-152662D01*
X95278Y-152370D01*
X96807Y-151204D01*
X97680Y-150038D01*
G01X107975Y-144787D02*
X114962D01*
X114307Y-142745D01*
X113215Y-141579D01*
X111687Y-140996D01*
X110158Y-141287D01*
X108848Y-142162D01*
X107975Y-144204D01*
X107538Y-145954D01*
Y-147704D01*
X107975Y-149454D01*
X109067Y-151204D01*
X110377Y-152370D01*
X111905Y-152662D01*
X113433Y-152079D01*
X114962Y-150329D01*
G01X125693Y-152662D02*
Y-140996D01*
G01Y-143329D02*
X126785Y-142162D01*
X127877Y-141287D01*
X129405Y-140996D01*
X130496Y-141287D01*
X131807Y-142162D01*
G01X142320Y-152662D02*
Y-135162D01*
G01Y-143912D02*
X143412Y-142162D01*
X144722Y-141287D01*
X146032Y-140996D01*
X147996Y-141579D01*
X149307Y-142745D01*
X150180Y-144787D01*
Y-147120D01*
X149743Y-149454D01*
X148870Y-151204D01*
X147342Y-152370D01*
X146032Y-152662D01*
X144722Y-152370D01*
X143412Y-151496D01*
X142320Y-150038D01*
G01X160475Y-144787D02*
X167462D01*
X166807Y-142745D01*
X165715Y-141579D01*
X164187Y-140996D01*
X162658Y-141287D01*
X161348Y-142162D01*
X160475Y-144204D01*
X160038Y-145954D01*
Y-147704D01*
X160475Y-149454D01*
X161567Y-151204D01*
X162877Y-152370D01*
X164405Y-152662D01*
X165933Y-152079D01*
X167462Y-150329D01*
G01X178193Y-152662D02*
Y-140996D01*
G01Y-143329D02*
X179285Y-142162D01*
X180377Y-141287D01*
X181905Y-140996D01*
X182996Y-141287D01*
X184307Y-142162D01*
G01X216250Y-140996D02*
Y-152662D01*
G01Y-136329D02*
X215813Y-136037D01*
Y-135454D01*
X216250Y-135162D01*
X216687Y-135454D01*
Y-136037D01*
X216250Y-136329D01*
G01X230475Y-150621D02*
X231567Y-151787D01*
X233095Y-152662D01*
X234405D01*
X235715Y-152079D01*
X236588Y-151204D01*
X237025Y-150038D01*
X236807Y-148287D01*
X235933Y-147412D01*
X232003Y-145662D01*
X231130Y-143620D01*
X231567Y-142162D01*
X232440Y-141287D01*
X233750Y-140996D01*
X235060Y-141287D01*
X236370Y-142162D01*
G01X265256Y-157037D02*
X266785Y-158204D01*
X268095Y-158495D01*
X269842Y-157912D01*
X271152Y-156454D01*
X271807Y-153828D01*
Y-140996D01*
G01Y-136329D02*
X271370Y-136037D01*
Y-135454D01*
X271807Y-135162D01*
X272243Y-135454D01*
Y-136037D01*
X271807Y-136329D01*
G01X282538Y-140996D02*
Y-149162D01*
X283412Y-151204D01*
X284722Y-152370D01*
X286250Y-152662D01*
X287778Y-152370D01*
X289088Y-151204D01*
X289962Y-149162D01*
G01Y-152662D02*
Y-140996D01*
G01X300475Y-150621D02*
X301567Y-151787D01*
X303095Y-152662D01*
X304405D01*
X305715Y-152079D01*
X306588Y-151204D01*
X307025Y-150038D01*
X306807Y-148287D01*
X305933Y-147412D01*
X302003Y-145662D01*
X301130Y-143620D01*
X301567Y-142162D01*
X302440Y-141287D01*
X303750Y-140996D01*
X305060Y-141287D01*
X306370Y-142162D01*
G01X321250Y-135162D02*
Y-152662D01*
G01X318193Y-140996D02*
X324307D01*
G01X354940Y-152662D02*
Y-137787D01*
X355377Y-136329D01*
X356250Y-135454D01*
X357560Y-135162D01*
X358870Y-135745D01*
X359525Y-137204D01*
G01X356905Y-142162D02*
X352538D01*
G01X373750Y-152662D02*
X372440Y-152370D01*
X371130Y-151204D01*
X370256Y-149162D01*
X369820Y-146829D01*
X370256Y-144495D01*
X371130Y-142454D01*
X372440Y-141287D01*
X373750Y-140996D01*
X375060Y-141287D01*
X376370Y-142454D01*
X377243Y-144495D01*
X377462Y-146829D01*
X377243Y-149162D01*
X376370Y-151204D01*
X375060Y-152370D01*
X373750Y-152662D01*
G01X388193D02*
Y-140996D01*
G01Y-143329D02*
X389285Y-142162D01*
X390377Y-141287D01*
X391905Y-140996D01*
X392996Y-141287D01*
X394307Y-142162D01*
G01X421665Y-157912D02*
X422975Y-158495D01*
X424722Y-157912D01*
X425813Y-156746D01*
X426687Y-155287D01*
X427996Y-150621D01*
X430835Y-140996D01*
G01X423848D02*
X427996Y-150621D01*
G01X443750Y-152662D02*
X442440Y-152370D01*
X441130Y-151204D01*
X440256Y-149162D01*
X439820Y-146829D01*
X440256Y-144495D01*
X441130Y-142454D01*
X442440Y-141287D01*
X443750Y-140996D01*
X445060Y-141287D01*
X446370Y-142454D01*
X447243Y-144495D01*
X447462Y-146829D01*
X447243Y-149162D01*
X446370Y-151204D01*
X445060Y-152370D01*
X443750Y-152662D01*
G01X457538Y-140996D02*
Y-149162D01*
X458412Y-151204D01*
X459722Y-152370D01*
X461250Y-152662D01*
X462778Y-152370D01*
X464088Y-151204D01*
X464962Y-149162D01*
G01Y-152662D02*
Y-140996D01*
G01X475693Y-152662D02*
Y-140996D01*
G01Y-143329D02*
X476785Y-142162D01*
X477877Y-141287D01*
X479405Y-140996D01*
X480496Y-141287D01*
X481807Y-142162D01*
G01X510693Y-152662D02*
Y-140996D01*
G01Y-143329D02*
X511785Y-142162D01*
X512877Y-141287D01*
X514405Y-140996D01*
X515496Y-141287D01*
X516807Y-142162D01*
G01X527975Y-144787D02*
X534962D01*
X534307Y-142745D01*
X533215Y-141579D01*
X531687Y-140996D01*
X530158Y-141287D01*
X528848Y-142162D01*
X527975Y-144204D01*
X527538Y-145954D01*
Y-147704D01*
X527975Y-149454D01*
X529067Y-151204D01*
X530377Y-152370D01*
X531905Y-152662D01*
X533433Y-152079D01*
X534962Y-150329D01*
G01X547440Y-152662D02*
Y-137787D01*
X547877Y-136329D01*
X548750Y-135454D01*
X550060Y-135162D01*
X551370Y-135745D01*
X552025Y-137204D01*
G01X549405Y-142162D02*
X545038D01*
G01X562975Y-144787D02*
X569962D01*
X569307Y-142745D01*
X568215Y-141579D01*
X566687Y-140996D01*
X565158Y-141287D01*
X563848Y-142162D01*
X562975Y-144204D01*
X562538Y-145954D01*
Y-147704D01*
X562975Y-149454D01*
X564067Y-151204D01*
X565377Y-152370D01*
X566905Y-152662D01*
X568433Y-152079D01*
X569962Y-150329D01*
G01X580693Y-152662D02*
Y-140996D01*
G01Y-143329D02*
X581785Y-142162D01*
X582877Y-141287D01*
X584405Y-140996D01*
X585496Y-141287D01*
X586807Y-142162D01*
G01X597975Y-144787D02*
X604962D01*
X604307Y-142745D01*
X603215Y-141579D01*
X601687Y-140996D01*
X600158Y-141287D01*
X598848Y-142162D01*
X597975Y-144204D01*
X597538Y-145954D01*
Y-147704D01*
X597975Y-149454D01*
X599067Y-151204D01*
X600377Y-152370D01*
X601905Y-152662D01*
X603433Y-152079D01*
X604962Y-150329D01*
G01X615038Y-152662D02*
Y-140996D01*
G01Y-143912D02*
X615912Y-142454D01*
X617222Y-141287D01*
X618968Y-140996D01*
X620496Y-141287D01*
X621807Y-142454D01*
X622462Y-144495D01*
Y-152662D01*
G01X639743Y-142454D02*
X638215Y-141287D01*
X636905Y-140996D01*
X635158Y-141579D01*
X633848Y-142745D01*
X632975Y-144787D01*
X632756Y-146829D01*
X632975Y-148871D01*
X633848Y-150621D01*
X635158Y-152079D01*
X636905Y-152662D01*
X638433Y-152079D01*
X639743Y-150912D01*
G01X650475Y-144787D02*
X657462D01*
X656807Y-142745D01*
X655715Y-141579D01*
X654187Y-140996D01*
X652658Y-141287D01*
X651348Y-142162D01*
X650475Y-144204D01*
X650038Y-145954D01*
Y-147704D01*
X650475Y-149454D01*
X651567Y-151204D01*
X652877Y-152370D01*
X654405Y-152662D01*
X655933Y-152079D01*
X657462Y-150329D01*
G01X688750Y-135162D02*
Y-152662D01*
G01X685693Y-140996D02*
X691807D01*
G01X706250Y-152662D02*
X704940Y-152370D01*
X703630Y-151204D01*
X702756Y-149162D01*
X702320Y-146829D01*
X702756Y-144495D01*
X703630Y-142454D01*
X704940Y-141287D01*
X706250Y-140996D01*
X707560Y-141287D01*
X708870Y-142454D01*
X709743Y-144495D01*
X709962Y-146829D01*
X709743Y-149162D01*
X708870Y-151204D01*
X707560Y-152370D01*
X706250Y-152662D01*
G01X739940D02*
Y-137787D01*
X740377Y-136329D01*
X741250Y-135454D01*
X742560Y-135162D01*
X743870Y-135745D01*
X744525Y-137204D01*
G01X741905Y-142162D02*
X737538D01*
G01X758750Y-140996D02*
Y-152662D01*
G01Y-136329D02*
X758313Y-136037D01*
Y-135454D01*
X758750Y-135162D01*
X759187Y-135454D01*
Y-136037D01*
X758750Y-136329D01*
G01X772538Y-152662D02*
Y-140996D01*
G01Y-143912D02*
X773412Y-142454D01*
X774722Y-141287D01*
X776468Y-140996D01*
X777996Y-141287D01*
X779307Y-142454D01*
X779962Y-144495D01*
Y-152662D01*
G01X797680Y-135162D02*
Y-152662D01*
G01Y-150038D02*
X796807Y-151496D01*
X795496Y-152370D01*
X793968Y-152662D01*
X792222Y-152079D01*
X790912Y-150621D01*
X790038Y-148871D01*
X789820Y-146829D01*
X790038Y-144787D01*
X790912Y-143037D01*
X792222Y-141579D01*
X793968Y-140996D01*
X795496Y-141287D01*
X796588Y-141871D01*
X797680Y-143037D01*
G01X828750Y-135162D02*
Y-152662D01*
G01X825693Y-140996D02*
X831807D01*
G01X842538Y-152662D02*
Y-135162D01*
G01Y-143620D02*
X843630Y-142162D01*
X844722Y-141287D01*
X846468Y-140996D01*
X847778Y-141287D01*
X849307Y-142454D01*
X849962Y-144204D01*
Y-152662D01*
G01X860475Y-144787D02*
X867462D01*
X866807Y-142745D01*
X865715Y-141579D01*
X864187Y-140996D01*
X862658Y-141287D01*
X861348Y-142162D01*
X860475Y-144204D01*
X860038Y-145954D01*
Y-147704D01*
X860475Y-149454D01*
X861567Y-151204D01*
X862877Y-152370D01*
X864405Y-152662D01*
X865933Y-152079D01*
X867462Y-150329D01*
G01X894165D02*
X895912Y-151787D01*
X897877Y-152662D01*
X899623D01*
X901370Y-151787D01*
X902680Y-150329D01*
X903335Y-148287D01*
X902898Y-146246D01*
X901807Y-144495D01*
X899842Y-143329D01*
X897222Y-142745D01*
X895693Y-141579D01*
X895038Y-139537D01*
X895475Y-137495D01*
X896567Y-136037D01*
X898095Y-135162D01*
X899623D01*
X901152Y-135745D01*
X902462Y-137204D01*
G01X920617Y-152662D02*
X911883D01*
Y-135162D01*
X920617D01*
G01X917123Y-143620D02*
X911883D01*
G01X951250Y-140996D02*
Y-152662D01*
G01Y-136329D02*
X950813Y-136037D01*
Y-135454D01*
X951250Y-135162D01*
X951687Y-135454D01*
Y-136037D01*
X951250Y-136329D01*
G01X962200Y-152662D02*
Y-140996D01*
G01Y-144204D02*
X962855Y-142745D01*
X963947Y-141579D01*
X965475Y-140996D01*
X967003Y-141579D01*
X968095Y-142745D01*
X968750Y-144204D01*
Y-152662D01*
G01Y-144204D02*
X969405Y-142745D01*
X970496Y-141579D01*
X972025Y-140996D01*
X973553Y-141579D01*
X974645Y-142745D01*
X975300Y-144495D01*
Y-152662D01*
G01X982320Y-158495D02*
Y-140996D01*
G01Y-143620D02*
X983412Y-142162D01*
X984503Y-141287D01*
X986250Y-140996D01*
X987778Y-141287D01*
X989307Y-142745D01*
X989962Y-144787D01*
X990180Y-146829D01*
X989962Y-148871D01*
X989307Y-150912D01*
X987996Y-152079D01*
X986250Y-152662D01*
X984722Y-152370D01*
X983193Y-151496D01*
X982320Y-150329D01*
G01X1000475Y-144787D02*
X1007462D01*
X1006807Y-142745D01*
X1005715Y-141579D01*
X1004187Y-140996D01*
X1002658Y-141287D01*
X1001348Y-142162D01*
X1000475Y-144204D01*
X1000038Y-145954D01*
Y-147704D01*
X1000475Y-149454D01*
X1001567Y-151204D01*
X1002877Y-152370D01*
X1004405Y-152662D01*
X1005933Y-152079D01*
X1007462Y-150329D01*
G01X1025180Y-135162D02*
Y-152662D01*
G01Y-150038D02*
X1024307Y-151496D01*
X1022996Y-152370D01*
X1021468Y-152662D01*
X1019722Y-152079D01*
X1018412Y-150621D01*
X1017538Y-148871D01*
X1017320Y-146829D01*
X1017538Y-144787D01*
X1018412Y-143037D01*
X1019722Y-141579D01*
X1021468Y-140996D01*
X1022996Y-141287D01*
X1024088Y-141871D01*
X1025180Y-143037D01*
G01X1042680Y-152662D02*
Y-140996D01*
G01Y-143037D02*
X1041807Y-141871D01*
X1040496Y-141287D01*
X1038968Y-140996D01*
X1037440Y-141579D01*
X1036130Y-142745D01*
X1035256Y-144495D01*
X1034820Y-146829D01*
X1035256Y-149162D01*
X1036130Y-150912D01*
X1037440Y-152079D01*
X1038968Y-152662D01*
X1040496Y-152370D01*
X1041807Y-151496D01*
X1042680Y-150329D01*
G01X1052538Y-152662D02*
Y-140996D01*
G01Y-143912D02*
X1053412Y-142454D01*
X1054722Y-141287D01*
X1056468Y-140996D01*
X1057996Y-141287D01*
X1059307Y-142454D01*
X1059962Y-144495D01*
Y-152662D01*
G01X1077243Y-142454D02*
X1075715Y-141287D01*
X1074405Y-140996D01*
X1072658Y-141579D01*
X1071348Y-142745D01*
X1070475Y-144787D01*
X1070256Y-146829D01*
X1070475Y-148871D01*
X1071348Y-150621D01*
X1072658Y-152079D01*
X1074405Y-152662D01*
X1075933Y-152079D01*
X1077243Y-150912D01*
G01X1087975Y-144787D02*
X1094962D01*
X1094307Y-142745D01*
X1093215Y-141579D01*
X1091687Y-140996D01*
X1090158Y-141287D01*
X1088848Y-142162D01*
X1087975Y-144204D01*
X1087538Y-145954D01*
Y-147704D01*
X1087975Y-149454D01*
X1089067Y-151204D01*
X1090377Y-152370D01*
X1091905Y-152662D01*
X1093433Y-152079D01*
X1094962Y-150329D01*
G01X1126250Y-135162D02*
Y-152662D01*
G01X1123193Y-140996D02*
X1129307D01*
G01X1140693Y-152662D02*
Y-140996D01*
G01Y-143329D02*
X1141785Y-142162D01*
X1142877Y-141287D01*
X1144405Y-140996D01*
X1145496Y-141287D01*
X1146807Y-142162D01*
G01X1165180Y-152662D02*
Y-140996D01*
G01Y-143037D02*
X1164307Y-141871D01*
X1162996Y-141287D01*
X1161468Y-140996D01*
X1159940Y-141579D01*
X1158630Y-142745D01*
X1157756Y-144495D01*
X1157320Y-146829D01*
X1157756Y-149162D01*
X1158630Y-150912D01*
X1159940Y-152079D01*
X1161468Y-152662D01*
X1162996Y-152370D01*
X1164307Y-151496D01*
X1165180Y-150329D01*
G01X1182243Y-142454D02*
X1180715Y-141287D01*
X1179405Y-140996D01*
X1177658Y-141579D01*
X1176348Y-142745D01*
X1175475Y-144787D01*
X1175256Y-146829D01*
X1175475Y-148871D01*
X1176348Y-150621D01*
X1177658Y-152079D01*
X1179405Y-152662D01*
X1180933Y-152079D01*
X1182243Y-150912D01*
G01X1192975Y-144787D02*
X1199962D01*
X1199307Y-142745D01*
X1198215Y-141579D01*
X1196687Y-140996D01*
X1195158Y-141287D01*
X1193848Y-142162D01*
X1192975Y-144204D01*
X1192538Y-145954D01*
Y-147704D01*
X1192975Y-149454D01*
X1194067Y-151204D01*
X1195377Y-152370D01*
X1196905Y-152662D01*
X1198433Y-152079D01*
X1199962Y-150329D01*
G01X1210475Y-150621D02*
X1211567Y-151787D01*
X1213095Y-152662D01*
X1214405D01*
X1215715Y-152079D01*
X1216588Y-151204D01*
X1217025Y-150038D01*
X1216807Y-148287D01*
X1215933Y-147412D01*
X1212003Y-145662D01*
X1211130Y-143620D01*
X1211567Y-142162D01*
X1212440Y-141287D01*
X1213750Y-140996D01*
X1215060Y-141287D01*
X1216370Y-142162D01*
G01X1248750Y-140996D02*
Y-152662D01*
G01Y-136329D02*
X1248313Y-136037D01*
Y-135454D01*
X1248750Y-135162D01*
X1249187Y-135454D01*
Y-136037D01*
X1248750Y-136329D01*
G01X1262538Y-152662D02*
Y-140996D01*
G01Y-143912D02*
X1263412Y-142454D01*
X1264722Y-141287D01*
X1266468Y-140996D01*
X1267996Y-141287D01*
X1269307Y-142454D01*
X1269962Y-144495D01*
Y-152662D01*
G01X1301250D02*
Y-135162D01*
G01X1322680Y-152662D02*
Y-140996D01*
G01Y-143037D02*
X1321807Y-141871D01*
X1320496Y-141287D01*
X1318968Y-140996D01*
X1317440Y-141579D01*
X1316130Y-142745D01*
X1315256Y-144495D01*
X1314820Y-146829D01*
X1315256Y-149162D01*
X1316130Y-150912D01*
X1317440Y-152079D01*
X1318968Y-152662D01*
X1320496Y-152370D01*
X1321807Y-151496D01*
X1322680Y-150329D01*
G01X1331665Y-157912D02*
X1332975Y-158495D01*
X1334722Y-157912D01*
X1335813Y-156746D01*
X1336687Y-155287D01*
X1337996Y-150621D01*
X1340835Y-140996D01*
G01X1333848D02*
X1337996Y-150621D01*
G01X1350475Y-144787D02*
X1357462D01*
X1356807Y-142745D01*
X1355715Y-141579D01*
X1354187Y-140996D01*
X1352658Y-141287D01*
X1351348Y-142162D01*
X1350475Y-144204D01*
X1350038Y-145954D01*
Y-147704D01*
X1350475Y-149454D01*
X1351567Y-151204D01*
X1352877Y-152370D01*
X1354405Y-152662D01*
X1355933Y-152079D01*
X1357462Y-150329D01*
G01X1368193Y-152662D02*
Y-140996D01*
G01Y-143329D02*
X1369285Y-142162D01*
X1370377Y-141287D01*
X1371905Y-140996D01*
X1372996Y-141287D01*
X1374307Y-142162D01*
G01X1401883Y-135162D02*
Y-152662D01*
X1410617D01*
G01X1419602Y-145371D02*
X1421130Y-143329D01*
X1422440Y-142162D01*
X1424187Y-141579D01*
X1425715Y-142162D01*
X1426807Y-143329D01*
X1427680Y-145079D01*
X1427898Y-147120D01*
X1427680Y-148871D01*
X1426807Y-150621D01*
X1425496Y-152079D01*
X1423968Y-152662D01*
X1422222Y-152079D01*
X1420693Y-150329D01*
X1419820Y-147704D01*
X1419602Y-144787D01*
X1420038Y-140996D01*
X1420693Y-138953D01*
X1421785Y-136912D01*
X1423313Y-135454D01*
X1424842Y-135162D01*
X1426370Y-135745D01*
X1427462Y-137204D01*
G01X1441250Y-153245D02*
X1440813Y-152954D01*
Y-152370D01*
X1441250Y-152079D01*
X1441687Y-152370D01*
Y-152954D01*
X1441250Y-153245D01*
G01X879036Y548599D02*
X880783Y547141D01*
X882748Y546266D01*
X884494D01*
X886241Y547141D01*
X887551Y548599D01*
X888206Y550641D01*
X887769Y552682D01*
X886678Y554433D01*
X884713Y555599D01*
X882093Y556183D01*
X880564Y557349D01*
X879909Y559391D01*
X880346Y561433D01*
X881438Y562891D01*
X882966Y563766D01*
X884494D01*
X886023Y563183D01*
X887333Y561724D01*
G01X905488Y546266D02*
X896754D01*
Y563766D01*
X905488D01*
G01X901994Y555308D02*
X896754D01*
G01X933501Y563766D02*
X938741D01*
G01X936121D02*
Y546266D01*
G01X933501D02*
X938741D01*
G01X947944D02*
Y563766D01*
X953621Y549183D01*
X959298Y563766D01*
Y546266D01*
G01X966754D02*
Y563766D01*
X971994D01*
X973741Y562891D01*
X975051Y560849D01*
X975488Y558516D01*
X975051Y556183D01*
X973959Y554433D01*
X971994Y553557D01*
X966754D01*
G01X992988Y546266D02*
X984254D01*
Y563766D01*
X992988D01*
G01X989494Y555308D02*
X984254D01*
G01X1001318Y546266D02*
Y563766D01*
X1005684D01*
X1007431Y562891D01*
X1008741Y561724D01*
X1009833Y559975D01*
X1010706Y557932D01*
X1010924Y555016D01*
X1010706Y552099D01*
X1009833Y550057D01*
X1008741Y548307D01*
X1007431Y547141D01*
X1005684Y546266D01*
X1001318D01*
G01X1018162D02*
X1023621Y563766D01*
X1029080Y546266D01*
G01X1027114Y552391D02*
X1020127D01*
G01X1036099Y546266D02*
Y563766D01*
X1046143Y546266D01*
Y563766D01*
G01X1063424Y562307D02*
X1062114Y563183D01*
X1060586Y563766D01*
X1058839D01*
X1056874Y562891D01*
X1055346Y561433D01*
X1054254Y559682D01*
X1053381Y556766D01*
X1053162Y554141D01*
X1053599Y551516D01*
X1054254Y549766D01*
X1055564Y548016D01*
X1057093Y546849D01*
X1058621Y546266D01*
X1060149D01*
X1061678Y546849D01*
X1062988Y547724D01*
X1064080Y548890D01*
G01X1080488Y546266D02*
X1071754D01*
Y563766D01*
X1080488D01*
G01X1076994Y555308D02*
X1071754D01*
G01X1111121Y563766D02*
Y546266D01*
G01X1106099Y563766D02*
X1116143D01*
G01X1123162Y546266D02*
X1128621Y563766D01*
X1134080Y546266D01*
G01X1132114Y552391D02*
X1125127D01*
G01X1147867Y555599D02*
X1148741Y556474D01*
X1149396Y557932D01*
X1149833Y559975D01*
X1149396Y561724D01*
X1148523Y562891D01*
X1146994Y563766D01*
X1141099D01*
Y546266D01*
X1148304D01*
X1149833Y547432D01*
X1150706Y549183D01*
X1151143Y551224D01*
X1150706Y553266D01*
X1149396Y555016D01*
X1147867Y555599D01*
X1141099D01*
G01X1159254Y563766D02*
Y546266D01*
X1167988D01*
G01X1185488D02*
X1176754D01*
Y563766D01*
X1185488D01*
G01X1181994Y555308D02*
X1176754D01*
G01X1198621Y545683D02*
X1198184Y545974D01*
Y546558D01*
X1198621Y546849D01*
X1199058Y546558D01*
Y545974D01*
X1198621Y545683D01*
G01Y553557D02*
X1198184Y553849D01*
Y554433D01*
X1198621Y554724D01*
X1199058Y554433D01*
Y553849D01*
X1198621Y553557D01*
G01X1229254Y563766D02*
Y546266D01*
X1237988D01*
G01X1246973Y553557D02*
X1248501Y555599D01*
X1249811Y556766D01*
X1251558Y557349D01*
X1253086Y556766D01*
X1254178Y555599D01*
X1255051Y553849D01*
X1255269Y551808D01*
X1255051Y550057D01*
X1254178Y548307D01*
X1252867Y546849D01*
X1251339Y546266D01*
X1249593Y546849D01*
X1248064Y548599D01*
X1247191Y551224D01*
X1246973Y554141D01*
X1247409Y557932D01*
X1248064Y559975D01*
X1249156Y562016D01*
X1250684Y563474D01*
X1252213Y563766D01*
X1253741Y563183D01*
X1254833Y561724D01*
G01X933518Y479590D02*
X934827Y478132D01*
X936356Y477258D01*
X938321Y476966D01*
X940286Y477549D01*
X941814Y478716D01*
X942906Y480757D01*
X943124Y483091D01*
X942688Y485424D01*
X941596Y486883D01*
X940067Y488049D01*
X938539Y488341D01*
X937011Y488049D01*
X935046Y486883D01*
X935701Y494466D01*
X941596D01*
G01X955821D02*
X954074Y493883D01*
X952764Y492424D01*
X951891Y490675D01*
X951236Y488341D01*
X951018Y485716D01*
X951236Y483091D01*
X951891Y480757D01*
X952764Y479007D01*
X954074Y477549D01*
X955821Y476966D01*
X957567Y477549D01*
X958878Y479007D01*
X959751Y480757D01*
X960406Y483091D01*
X960624Y485716D01*
X960406Y488341D01*
X959751Y490675D01*
X958878Y492424D01*
X957567Y493883D01*
X955821Y494466D01*
G01X973321Y476383D02*
X972884Y476674D01*
Y477258D01*
X973321Y477549D01*
X973758Y477258D01*
Y476674D01*
X973321Y476383D01*
G01X990821Y494466D02*
X989074Y493883D01*
X987764Y492424D01*
X986891Y490675D01*
X986236Y488341D01*
X986018Y485716D01*
X986236Y483091D01*
X986891Y480757D01*
X987764Y479007D01*
X989074Y477549D01*
X990821Y476966D01*
X992567Y477549D01*
X993878Y479007D01*
X994751Y480757D01*
X995406Y483091D01*
X995624Y485716D01*
X995406Y488341D01*
X994751Y490675D01*
X993878Y492424D01*
X992567Y493883D01*
X990821Y494466D01*
G01X900701Y529116D02*
X905941D01*
G01X903321D02*
Y511616D01*
G01X900701D02*
X905941D01*
G01X915144D02*
Y529116D01*
X920821Y514533D01*
X926498Y529116D01*
Y511616D01*
G01X933954D02*
Y529116D01*
X939194D01*
X940941Y528241D01*
X942251Y526199D01*
X942688Y523866D01*
X942251Y521533D01*
X941159Y519783D01*
X939194Y518907D01*
X933954D01*
G01X954729Y505783D02*
X952546Y508699D01*
X951454Y511616D01*
Y523282D01*
X952546Y526199D01*
X954729Y529116D01*
G01X973321Y511616D02*
X971574Y511908D01*
X970046Y513074D01*
X968736Y514824D01*
X967862Y516866D01*
X967426Y519199D01*
Y521533D01*
X967862Y523866D01*
X968736Y525908D01*
X970046Y527657D01*
X971574Y528824D01*
X973321Y529116D01*
X975067Y528824D01*
X976596Y527657D01*
X977906Y525908D01*
X978780Y523866D01*
X979216Y521533D01*
Y519199D01*
X978780Y516866D01*
X977906Y514824D01*
X976596Y513074D01*
X975067Y511908D01*
X973321Y511616D01*
G01X987109D02*
Y529116D01*
G01Y520658D02*
X988201Y522116D01*
X989293Y522991D01*
X991039Y523282D01*
X992349Y522991D01*
X993878Y521824D01*
X994533Y520074D01*
Y511616D01*
G01X1001771D02*
Y523282D01*
G01Y520074D02*
X1002426Y521533D01*
X1003518Y522699D01*
X1005046Y523282D01*
X1006574Y522699D01*
X1007666Y521533D01*
X1008321Y520074D01*
Y511616D01*
G01Y520074D02*
X1008976Y521533D01*
X1010067Y522699D01*
X1011596Y523282D01*
X1013124Y522699D01*
X1014216Y521533D01*
X1014871Y519783D01*
Y511616D01*
G01X1026913Y505783D02*
X1029096Y508699D01*
X1030188Y511616D01*
Y523282D01*
X1029096Y526199D01*
X1026913Y529116D01*
G01X1071771D02*
X1074827Y511616D01*
X1078321Y529116D01*
X1081814Y511616D01*
X1084871Y529116D01*
G01X1093201D02*
X1098441D01*
G01X1095821D02*
Y511616D01*
G01X1093201D02*
X1098441D01*
G01X1108518D02*
Y529116D01*
X1112884D01*
X1114631Y528241D01*
X1115941Y527074D01*
X1117033Y525325D01*
X1117906Y523282D01*
X1118124Y520366D01*
X1117906Y517449D01*
X1117033Y515407D01*
X1115941Y513657D01*
X1114631Y512491D01*
X1112884Y511616D01*
X1108518D01*
G01X1130821Y529116D02*
Y511616D01*
G01X1125799Y529116D02*
X1135843D01*
G01X1143736Y511616D02*
Y529116D01*
G01X1152906D02*
Y511616D01*
G01Y520366D02*
X1143736D01*
G01X1164729Y505783D02*
X1162546Y508699D01*
X1161454Y511616D01*
Y523282D01*
X1162546Y526199D01*
X1164729Y529116D01*
G01X1176771Y511616D02*
Y523282D01*
G01Y520074D02*
X1177426Y521533D01*
X1178518Y522699D01*
X1180046Y523282D01*
X1181574Y522699D01*
X1182666Y521533D01*
X1183321Y520074D01*
Y511616D01*
G01Y520074D02*
X1183976Y521533D01*
X1185067Y522699D01*
X1186596Y523282D01*
X1188124Y522699D01*
X1189216Y521533D01*
X1189871Y519783D01*
Y511616D01*
G01X1200821Y523282D02*
Y511616D01*
G01Y527949D02*
X1200384Y528241D01*
Y528824D01*
X1200821Y529116D01*
X1201258Y528824D01*
Y528241D01*
X1200821Y527949D01*
G01X1218321Y511616D02*
Y529116D01*
G01X1232546Y513657D02*
X1233638Y512491D01*
X1235166Y511616D01*
X1236476D01*
X1237786Y512199D01*
X1238659Y513074D01*
X1239096Y514240D01*
X1238878Y515991D01*
X1238004Y516866D01*
X1234074Y518616D01*
X1233201Y520658D01*
X1233638Y522116D01*
X1234511Y522991D01*
X1235821Y523282D01*
X1237131Y522991D01*
X1238441Y522116D01*
G01X1254413Y505783D02*
X1256596Y508699D01*
X1257688Y511616D01*
Y523282D01*
X1256596Y526199D01*
X1254413Y529116D01*
G01X1143518Y479590D02*
X1144827Y478132D01*
X1146356Y477258D01*
X1148321Y476966D01*
X1150286Y477549D01*
X1151814Y478716D01*
X1152906Y480757D01*
X1153124Y483091D01*
X1152688Y485424D01*
X1151596Y486883D01*
X1150067Y488049D01*
X1148539Y488341D01*
X1147011Y488049D01*
X1145046Y486883D01*
X1145701Y494466D01*
X1151596D01*
G01X1165821Y476383D02*
X1165384Y476674D01*
Y477258D01*
X1165821Y477549D01*
X1166258Y477258D01*
Y476674D01*
X1165821Y476383D01*
G01X1183321Y494466D02*
X1181574Y493883D01*
X1180264Y492424D01*
X1179391Y490675D01*
X1178736Y488341D01*
X1178518Y485716D01*
X1178736Y483091D01*
X1179391Y480757D01*
X1180264Y479007D01*
X1181574Y477549D01*
X1183321Y476966D01*
X1185067Y477549D01*
X1186378Y479007D01*
X1187251Y480757D01*
X1187906Y483091D01*
X1188124Y485716D01*
X1187906Y488341D01*
X1187251Y490675D01*
X1186378Y492424D01*
X1185067Y493883D01*
X1183321Y494466D01*
G01X1318736Y479299D02*
X1320483Y477841D01*
X1322448Y476966D01*
X1324194D01*
X1325941Y477841D01*
X1327251Y479299D01*
X1327906Y481341D01*
X1327469Y483382D01*
X1326378Y485133D01*
X1324413Y486299D01*
X1321793Y486883D01*
X1320264Y488049D01*
X1319609Y490091D01*
X1320046Y492133D01*
X1321138Y493591D01*
X1322666Y494466D01*
X1324194D01*
X1325723Y493883D01*
X1327033Y492424D01*
G01X1345188Y476966D02*
X1336454D01*
Y494466D01*
X1345188D01*
G01X1341694Y486008D02*
X1336454D01*
G01X1305821Y529116D02*
Y511616D01*
G01X1300799Y529116D02*
X1310843D01*
G01X1323321Y511616D02*
Y519491D01*
X1318954Y529116D01*
G01X1327688D02*
X1323321Y519491D01*
G01X1336454Y511616D02*
Y529116D01*
X1341694D01*
X1343441Y528241D01*
X1344751Y526199D01*
X1345188Y523866D01*
X1344751Y521533D01*
X1343659Y519783D01*
X1341694Y518907D01*
X1336454D01*
G01X1362688Y511616D02*
X1353954D01*
Y529116D01*
X1362688D01*
G01X1359194Y520658D02*
X1353954D01*
G01X1406454Y511616D02*
Y529116D01*
X1411913D01*
X1413659Y528241D01*
X1414751Y527074D01*
X1415188Y524741D01*
X1414751Y522407D01*
X1413441Y520949D01*
X1411913Y520074D01*
X1406454D01*
G01X1411913D02*
X1415188Y511616D01*
G01X1425046Y519491D02*
X1432033D01*
X1431378Y521533D01*
X1430286Y522699D01*
X1428758Y523282D01*
X1427229Y522991D01*
X1425919Y522116D01*
X1425046Y520074D01*
X1424609Y518324D01*
Y516574D01*
X1425046Y514824D01*
X1426138Y513074D01*
X1427448Y511908D01*
X1428976Y511616D01*
X1430504Y512199D01*
X1432033Y513949D01*
G01X1444511Y511616D02*
Y526491D01*
X1444948Y527949D01*
X1445821Y528824D01*
X1447131Y529116D01*
X1448441Y528533D01*
X1449096Y527074D01*
G01X1446476Y522116D02*
X1442109D01*
G01X1463321Y511033D02*
X1462884Y511324D01*
Y511908D01*
X1463321Y512199D01*
X1463758Y511908D01*
Y511324D01*
X1463321Y511033D01*
G01X1493954Y511616D02*
Y529116D01*
X1499194D01*
X1500941Y528241D01*
X1502251Y526199D01*
X1502688Y523866D01*
X1502251Y521533D01*
X1501159Y519783D01*
X1499194Y518907D01*
X1493954D01*
G01X1515821Y511616D02*
Y529116D01*
G01X1537251Y511616D02*
Y523282D01*
G01Y521241D02*
X1536378Y522407D01*
X1535067Y522991D01*
X1533539Y523282D01*
X1532011Y522699D01*
X1530701Y521533D01*
X1529827Y519783D01*
X1529391Y517449D01*
X1529827Y515116D01*
X1530701Y513366D01*
X1532011Y512199D01*
X1533539Y511616D01*
X1535067Y511908D01*
X1536378Y512782D01*
X1537251Y513949D01*
G01X1547109Y511616D02*
Y523282D01*
G01Y520366D02*
X1547983Y521824D01*
X1549293Y522991D01*
X1551039Y523282D01*
X1552567Y522991D01*
X1553878Y521824D01*
X1554533Y519783D01*
Y511616D01*
G01X1565046Y519491D02*
X1572033D01*
X1571378Y521533D01*
X1570286Y522699D01*
X1568758Y523282D01*
X1567229Y522991D01*
X1565919Y522116D01*
X1565046Y520074D01*
X1564609Y518324D01*
Y516574D01*
X1565046Y514824D01*
X1566138Y513074D01*
X1567448Y511908D01*
X1568976Y511616D01*
X1570504Y512199D01*
X1572033Y513949D01*
G01X1450204Y494466D02*
Y476966D01*
X1458938D01*
G01X1467268Y479590D02*
X1468577Y478132D01*
X1470106Y477258D01*
X1472071Y476966D01*
X1474036Y477549D01*
X1475564Y478716D01*
X1476656Y480757D01*
X1476874Y483091D01*
X1476438Y485424D01*
X1475346Y486883D01*
X1473817Y488049D01*
X1472289Y488341D01*
X1470761Y488049D01*
X1468796Y486883D01*
X1469451Y494466D01*
X1475346D01*
G01X1485641Y476383D02*
X1493501Y494466D01*
G01X1502704D02*
Y476966D01*
X1511438D01*
G01X1524134D02*
X1524571Y480757D01*
X1525226Y483966D01*
X1526099Y486883D01*
X1527191Y490091D01*
X1528938Y494466D01*
X1520204D01*
G01X1686121Y488632D02*
Y476966D01*
G01Y493299D02*
X1685684Y493591D01*
Y494174D01*
X1686121Y494466D01*
X1686558Y494174D01*
Y493591D01*
X1686121Y493299D01*
G01X1700346Y479007D02*
X1701438Y477841D01*
X1702966Y476966D01*
X1704276D01*
X1705586Y477549D01*
X1706459Y478424D01*
X1706896Y479590D01*
X1706678Y481341D01*
X1705804Y482216D01*
X1701874Y483966D01*
X1701001Y486008D01*
X1701438Y487466D01*
X1702311Y488341D01*
X1703621Y488632D01*
X1704931Y488341D01*
X1706241Y487466D01*
G01X1733599Y476966D02*
Y494466D01*
X1743643Y476966D01*
Y494466D01*
G01X1756121Y476966D02*
X1754374Y477258D01*
X1752846Y478424D01*
X1751536Y480174D01*
X1750662Y482216D01*
X1750226Y484549D01*
Y486883D01*
X1750662Y489216D01*
X1751536Y491258D01*
X1752846Y493007D01*
X1754374Y494174D01*
X1756121Y494466D01*
X1757867Y494174D01*
X1759396Y493007D01*
X1760706Y491258D01*
X1761580Y489216D01*
X1762016Y486883D01*
Y484549D01*
X1761580Y482216D01*
X1760706Y480174D01*
X1759396Y478424D01*
X1757867Y477258D01*
X1756121Y476966D01*
G01X1773621Y494466D02*
Y476966D01*
G01X1768599Y494466D02*
X1778643D01*
G01X1804909Y488632D02*
Y480466D01*
X1805783Y478424D01*
X1807093Y477258D01*
X1808621Y476966D01*
X1810149Y477258D01*
X1811459Y478424D01*
X1812333Y480466D01*
G01Y476966D02*
Y488632D01*
G01X1822846Y479007D02*
X1823938Y477841D01*
X1825466Y476966D01*
X1826776D01*
X1828086Y477549D01*
X1828959Y478424D01*
X1829396Y479590D01*
X1829178Y481341D01*
X1828304Y482216D01*
X1824374Y483966D01*
X1823501Y486008D01*
X1823938Y487466D01*
X1824811Y488341D01*
X1826121Y488632D01*
X1827431Y488341D01*
X1828741Y487466D01*
G01X1840346Y484841D02*
X1847333D01*
X1846678Y486883D01*
X1845586Y488049D01*
X1844058Y488632D01*
X1842529Y488341D01*
X1841219Y487466D01*
X1840346Y485424D01*
X1839909Y483674D01*
Y481924D01*
X1840346Y480174D01*
X1841438Y478424D01*
X1842748Y477258D01*
X1844276Y476966D01*
X1845804Y477549D01*
X1847333Y479299D01*
G01X1865051Y494466D02*
Y476966D01*
G01Y479590D02*
X1864178Y478132D01*
X1862867Y477258D01*
X1861339Y476966D01*
X1859593Y477549D01*
X1858283Y479007D01*
X1857409Y480757D01*
X1857191Y482799D01*
X1857409Y484841D01*
X1858283Y486591D01*
X1859593Y488049D01*
X1861339Y488632D01*
X1862867Y488341D01*
X1863959Y487757D01*
X1865051Y486591D01*
G01X1611318Y511033D02*
X1620924Y523866D01*
G01X1616121Y526199D02*
Y508699D01*
G01X1620924Y511033D02*
X1611318Y523866D01*
G01X1609571Y517449D02*
X1622671D01*
G01X1648283D02*
X1653959D01*
G01X1681318Y511616D02*
Y529116D01*
X1685684D01*
X1687431Y528241D01*
X1688741Y527074D01*
X1689833Y525325D01*
X1690706Y523282D01*
X1690924Y520366D01*
X1690706Y517449D01*
X1689833Y515407D01*
X1688741Y513657D01*
X1687431Y512491D01*
X1685684Y511616D01*
X1681318D01*
G01X1700346Y519491D02*
X1707333D01*
X1706678Y521533D01*
X1705586Y522699D01*
X1704058Y523282D01*
X1702529Y522991D01*
X1701219Y522116D01*
X1700346Y520074D01*
X1699909Y518324D01*
Y516574D01*
X1700346Y514824D01*
X1701438Y513074D01*
X1702748Y511908D01*
X1704276Y511616D01*
X1705804Y512199D01*
X1707333Y513949D01*
G01X1717409Y511616D02*
Y523282D01*
G01Y520366D02*
X1718283Y521824D01*
X1719593Y522991D01*
X1721339Y523282D01*
X1722867Y522991D01*
X1724178Y521824D01*
X1724833Y519783D01*
Y511616D01*
G01X1738621D02*
X1737311Y511908D01*
X1736001Y513074D01*
X1735127Y515116D01*
X1734691Y517449D01*
X1735127Y519783D01*
X1736001Y521824D01*
X1737311Y522991D01*
X1738621Y523282D01*
X1739931Y522991D01*
X1741241Y521824D01*
X1742114Y519783D01*
X1742333Y517449D01*
X1742114Y515116D01*
X1741241Y513074D01*
X1739931Y511908D01*
X1738621Y511616D01*
G01X1756121Y529116D02*
Y511616D01*
G01X1753064Y523282D02*
X1759178D01*
G01X1770346Y519491D02*
X1777333D01*
X1776678Y521533D01*
X1775586Y522699D01*
X1774058Y523282D01*
X1772529Y522991D01*
X1771219Y522116D01*
X1770346Y520074D01*
X1769909Y518324D01*
Y516574D01*
X1770346Y514824D01*
X1771438Y513074D01*
X1772748Y511908D01*
X1774276Y511616D01*
X1775804Y512199D01*
X1777333Y513949D01*
G01X1787846Y513657D02*
X1788938Y512491D01*
X1790466Y511616D01*
X1791776D01*
X1793086Y512199D01*
X1793959Y513074D01*
X1794396Y514240D01*
X1794178Y515991D01*
X1793304Y516866D01*
X1789374Y518616D01*
X1788501Y520658D01*
X1788938Y522116D01*
X1789811Y522991D01*
X1791121Y523282D01*
X1792431Y522991D01*
X1793741Y522116D01*
G01X1826121Y529116D02*
Y511616D01*
G01X1823064Y523282D02*
X1829178D01*
G01X1839909Y511616D02*
Y529116D01*
G01Y520658D02*
X1841001Y522116D01*
X1842093Y522991D01*
X1843839Y523282D01*
X1845149Y522991D01*
X1846678Y521824D01*
X1847333Y520074D01*
Y511616D01*
G01X1865051D02*
Y523282D01*
G01Y521241D02*
X1864178Y522407D01*
X1862867Y522991D01*
X1861339Y523282D01*
X1859811Y522699D01*
X1858501Y521533D01*
X1857627Y519783D01*
X1857191Y517449D01*
X1857627Y515116D01*
X1858501Y513366D01*
X1859811Y512199D01*
X1861339Y511616D01*
X1862867Y511908D01*
X1864178Y512782D01*
X1865051Y513949D01*
G01X1878621Y529116D02*
Y511616D01*
G01X1875564Y523282D02*
X1881678D01*
G01X1913621Y529116D02*
Y511616D01*
G01X1910564Y523282D02*
X1916678D01*
G01X1927409Y511616D02*
Y529116D01*
G01Y520658D02*
X1928501Y522116D01*
X1929593Y522991D01*
X1931339Y523282D01*
X1932649Y522991D01*
X1934178Y521824D01*
X1934833Y520074D01*
Y511616D01*
G01X1948621Y523282D02*
Y511616D01*
G01Y527949D02*
X1948184Y528241D01*
Y528824D01*
X1948621Y529116D01*
X1949058Y528824D01*
Y528241D01*
X1948621Y527949D01*
G01X1962846Y513657D02*
X1963938Y512491D01*
X1965466Y511616D01*
X1966776D01*
X1968086Y512199D01*
X1968959Y513074D01*
X1969396Y514240D01*
X1969178Y515991D01*
X1968304Y516866D01*
X1964374Y518616D01*
X1963501Y520658D01*
X1963938Y522116D01*
X1964811Y522991D01*
X1966121Y523282D01*
X1967431Y522991D01*
X1968741Y522116D01*
G01X1998501Y529116D02*
X2003741D01*
G01X2001121D02*
Y511616D01*
G01X1998501D02*
X2003741D01*
G01X2012071D02*
Y523282D01*
G01Y520074D02*
X2012726Y521533D01*
X2013818Y522699D01*
X2015346Y523282D01*
X2016874Y522699D01*
X2017966Y521533D01*
X2018621Y520074D01*
Y511616D01*
G01Y520074D02*
X2019276Y521533D01*
X2020367Y522699D01*
X2021896Y523282D01*
X2023424Y522699D01*
X2024516Y521533D01*
X2025171Y519783D01*
Y511616D01*
G01X2032191Y505783D02*
Y523282D01*
G01Y520658D02*
X2033283Y522116D01*
X2034374Y522991D01*
X2036121Y523282D01*
X2037649Y522991D01*
X2039178Y521533D01*
X2039833Y519491D01*
X2040051Y517449D01*
X2039833Y515407D01*
X2039178Y513366D01*
X2037867Y512199D01*
X2036121Y511616D01*
X2034593Y511908D01*
X2033064Y512782D01*
X2032191Y513949D01*
G01X2050346Y519491D02*
X2057333D01*
X2056678Y521533D01*
X2055586Y522699D01*
X2054058Y523282D01*
X2052529Y522991D01*
X2051219Y522116D01*
X2050346Y520074D01*
X2049909Y518324D01*
Y516574D01*
X2050346Y514824D01*
X2051438Y513074D01*
X2052748Y511908D01*
X2054276Y511616D01*
X2055804Y512199D01*
X2057333Y513949D01*
G01X2075051Y529116D02*
Y511616D01*
G01Y514240D02*
X2074178Y512782D01*
X2072867Y511908D01*
X2071339Y511616D01*
X2069593Y512199D01*
X2068283Y513657D01*
X2067409Y515407D01*
X2067191Y517449D01*
X2067409Y519491D01*
X2068283Y521241D01*
X2069593Y522699D01*
X2071339Y523282D01*
X2072867Y522991D01*
X2073959Y522407D01*
X2075051Y521241D01*
G01X2092551Y511616D02*
Y523282D01*
G01Y521241D02*
X2091678Y522407D01*
X2090367Y522991D01*
X2088839Y523282D01*
X2087311Y522699D01*
X2086001Y521533D01*
X2085127Y519783D01*
X2084691Y517449D01*
X2085127Y515116D01*
X2086001Y513366D01*
X2087311Y512199D01*
X2088839Y511616D01*
X2090367Y511908D01*
X2091678Y512782D01*
X2092551Y513949D01*
G01X2102409Y511616D02*
Y523282D01*
G01Y520366D02*
X2103283Y521824D01*
X2104593Y522991D01*
X2106339Y523282D01*
X2107867Y522991D01*
X2109178Y521824D01*
X2109833Y519783D01*
Y511616D01*
G01X2127114Y521824D02*
X2125586Y522991D01*
X2124276Y523282D01*
X2122529Y522699D01*
X2121219Y521533D01*
X2120346Y519491D01*
X2120127Y517449D01*
X2120346Y515407D01*
X2121219Y513657D01*
X2122529Y512199D01*
X2124276Y511616D01*
X2125804Y512199D01*
X2127114Y513366D01*
G01X2137846Y519491D02*
X2144833D01*
X2144178Y521533D01*
X2143086Y522699D01*
X2141558Y523282D01*
X2140029Y522991D01*
X2138719Y522116D01*
X2137846Y520074D01*
X2137409Y518324D01*
Y516574D01*
X2137846Y514824D01*
X2138938Y513074D01*
X2140248Y511908D01*
X2141776Y511616D01*
X2143304Y512199D01*
X2144833Y513949D01*
G01X20103Y-86244D02*
G03I-4291J0D01*
G01X0Y-87362D02*
G03X15000Y-102362I15000J0D01*
G01X0Y-11811D02*
Y-87362D01*
G01X3937Y-7874D02*
G03X0Y-11811I0J-3937D01*
G01X15748Y-7874D02*
X3937D01*
G01X0Y7874D02*
G03X7874Y0I7874J0D01*
G01X818897D02*
X7874D01*
G01X0Y7874D02*
Y562992D01*
G01X7874Y570866D02*
G03X0Y562992I0J-7874D01*
G01X7874Y570866D02*
X326781D01*
G01X312004Y-102362D02*
X15000D01*
G01X46456Y0D02*
G03Y-7874I0J-3937D01*
G01X15748D02*
G03Y0I0J3937D01*
G01X287400Y-7874D02*
X46456D01*
G01X40452Y499724D02*
G03I-3051J0D01*
G01X41535Y535157D02*
G03I-4134J0D01*
G01X44685Y517441D02*
G03I-7284J0D01*
G01X121082Y39055D02*
G03I-5019J0D01*
G01X120807Y14567D02*
G03I-4744J0D01*
G01X319878Y-102362D02*
G03X312004I-3937J0D01*
G01X811771D02*
X319878D01*
G01X326770Y0D02*
G03Y-7874I0J-3937D01*
G01X287400D02*
G03Y0I0J3937D01*
G01X302165Y531496D02*
G03I-6890J0D01*
G01X597707Y-7874D02*
X326770D01*
G01X379921Y156220D02*
G03I-5906J0D01*
G01X342529Y530315D02*
G03X334655I-3937J0D01*
G01X342529Y520720D02*
G03X352474Y509057I11811J0D01*
G01X334655Y520720D02*
G03X351230Y501282I19685J0D01*
G01X384484Y503937D02*
X352475Y509057D01*
G01X383858Y496063D02*
X351231Y501282D01*
G01X442287Y503937D02*
X384484D01*
G01X442913Y496063D02*
X383858D01*
G01X342529Y530315D02*
Y520720D01*
G01X334655Y562992D02*
Y520720D01*
G01X346466Y570866D02*
G03X342529Y566929I0J-3937D01*
G01X334655Y555512D02*
G03X342529I3937J0D01*
G01X346466Y570866D02*
X480325D01*
G01X334655Y562992D02*
G03X326781Y570866I-7874J0D01*
G01X342529Y566929D02*
Y555512D01*
G01X415943Y539991D02*
G03I-4291J0D01*
G01X474316Y509060D02*
X442287Y503937D01*
G01X475560Y501285D02*
X442913Y496063D01*
G01X492136Y530315D02*
G03X484262I-3937J0D01*
G01X474316Y509060D02*
G03X484262Y520723I-1865J11663D01*
G01X475560Y501285D02*
G03X492136Y520723I-3109J19438D01*
G01X484262Y530315D02*
Y520723D01*
G01X492136Y562992D02*
Y520723D01*
G01X484262Y566929D02*
G03X480325Y570866I-3937J0D01*
G01X484262Y555512D02*
G03X492136I3937J0D01*
G01X500010Y570866D02*
G03X492136Y562992I0J-7874D01*
G01X500010Y570866D02*
X818897D01*
G01X484262Y566929D02*
Y555512D01*
G01X537401Y371299D02*
G03I-5905J0D01*
G01X538386Y531496D02*
G03I-6890J0D01*
G01X628416Y0D02*
G03Y-7874I0J-3937D01*
G01X597707D02*
G03Y0I0J3937D01*
G01X780315Y-7874D02*
X628416D01*
G01X602362Y116141D02*
G03I-5906J0D01*
G01X817003Y-86834D02*
G03I-4292J0D01*
G01X811771Y-102362D02*
G03X826771Y-87362I0J15000D01*
G01X811023Y0D02*
G03Y-7874I0J-3937D01*
G01X780315D02*
G03Y0I0J3937D01*
G01X822834Y-7874D02*
X811023D01*
G01X818897Y0D02*
G03X826771Y7874I0J7874D01*
G01X818897Y0D02*
X807086D01*
G01X787401Y198819D02*
G03I-5905J0D01*
G01X792421Y499724D02*
G03I-3051J0D01*
G01X793504Y535157D02*
G03I-4134J0D01*
G01X796653Y517441D02*
G03I-7283J0D01*
G01X826771Y562992D02*
G03X818897Y570866I-7874J0D01*
G01X826771Y-11811D02*
Y-87362D01*
G01Y-11811D02*
G03X822834Y-7874I-3937J0D01*
G01X826771Y562992D02*
Y7874D01*
M02*
